FILE_TYPE = MACRO_DRAWING;
SET COLOR_WIRE YELLOW;
SET COLOR_PROP ORANGE;
SET COLOR_DOT WHITE;
SET COLOR_ARC YELLOW;
SET COLOR_BODY GREEN;
SET COLOR_NOTE PURPLE;
SET PROP_DISPLAY VALUE;
SET PAGE_NUMBER P102;
FORCEADD UNIVERSAL_GND..1
(-2600 -200);
FORCEPROP 3 LASTPIN (-2600 -150) SIG_NAME GND\g
J 0
(-2590 -140);
DISPLAY 0.659574 (-2590 -140);
PAINT MONO (-2590 -140);
DISPLAY INVISIBLE (-2590 -140);
FORCEPROP 1 LAST PATH I1
J 0
(-2525 -200);
DISPLAY 0.872340 (-2525 -200);
PAINT AQUA (-2525 -200);
DISPLAY INVISIBLE (-2525 -200);
FORCEPROP 1 LAST HDL_POWER GND
J 1
(-2575 -275);
DISPLAY 0.872340 (-2575 -275);
PAINT GREEN (-2575 -275);
DISPLAY INVISIBLE (-2575 -275);
FORCEPROP 2 LAST CDS_LIB logical_power
J 0
(-2600 -200);
PAINT MONO (-2600 -200);
DISPLAY INVISIBLE (-2600 -200);
FORCEADD OFFPAGE..1
(-3650 1625);
FORCEPROP 2 LAST $XR7 105 
J 0
(-3992 1661);
DISPLAY 0.638298 (-3992 1661);
PAINT MONO (-3992 1661);
FORCEPROP 2 LAST $XR6 104 
J 0
(-4142 1589);
DISPLAY 0.638298 (-4142 1589);
PAINT MONO (-4142 1589);
FORCEPROP 2 LAST $XR5 103 
J 0
(-4022 1589);
DISPLAY 0.638298 (-4022 1589);
PAINT MONO (-4022 1589);
FORCEPROP 2 LAST $XR4 101 
J 0
(-3902 1589);
DISPLAY 0.638298 (-3902 1589);
PAINT MONO (-3902 1589);
FORCEPROP 2 LAST $XR3 100 
J 0
(-4202 1625);
DISPLAY 0.638298 (-4202 1625);
PAINT MONO (-4202 1625);
FORCEPROP 2 LAST $XR2 99 
J 0
(-4082 1625);
DISPLAY 0.638298 (-4082 1625);
PAINT MONO (-4082 1625);
FORCEPROP 2 LAST $XR1 98 
J 0
(-3992 1625);
DISPLAY 0.638298 (-3992 1625);
PAINT MONO (-3992 1625);
FORCEPROP 2 LAST $XR0 230 
J 0
(-3902 1625);
DISPLAY 0.638298 (-3902 1625);
PAINT MONO (-3902 1625);
FORCEPROP 2 LAST CDS_LIB standard
J 0
(-3650 1625);
PAINT MONO (-3650 1625);
DISPLAY INVISIBLE (-3650 1625);
FORCEPROP 1 LAST OFFPAGE TRUE
J 0
(-3325 1500);
DISPLAY 0.872340 (-3325 1500);
DISPLAY INVISIBLE (-3325 1500);
FORCEPROP 1 LAST COMMENT_BODY TRUE
J 0
(-3525 1525);
DISPLAY 0.872340 (-3525 1525);
PAINT GREEN (-3525 1525);
DISPLAY INVISIBLE (-3525 1525);
FORCEPROP 2 LAST PATH I10
J 0
(-3600 1700);
DISPLAY 1.021277 (-3600 1700);
DISPLAY INVISIBLE (-3600 1700);
FORCEADD TAP..1
(-1175 3375);
FORCEPROP 3 LASTPIN (-1225 3375) SIG_NAME M_C_CPU1_SA_DQ<15>
J 0
(-1215 3385);
DISPLAY 0.659574 (-1215 3385);
PAINT MONO (-1215 3385);
DISPLAY INVISIBLE (-1215 3385);
FORCEPROP 1 LASTPIN (-1225 3375) BN 15
J 0
(-1237 3383);
DISPLAY 0.680851 (-1237 3383);
PAINT GREEN (-1237 3383);
FORCEPROP 2 LAST CDS_LIB standard
J 0
(-1175 3375);
PAINT MONO (-1175 3375);
DISPLAY INVISIBLE (-1175 3375);
FORCEPROP 1 LAST BODY_TYPE PLUMBING
J 0
(-1175 3425);
DISPLAY 0.872340 (-1175 3425);
PAINT GREEN (-1175 3425);
DISPLAY INVISIBLE (-1175 3425);
FORCEPROP 1 LAST HDL_TAP TRUE
J 0
(-850 3250);
DISPLAY 0.872340 (-850 3250);
DISPLAY INVISIBLE (-850 3250);
FORCEPROP 1 LAST PATH I100
J 0
(-1177 3375);
DISPLAY 0.872340 (-1177 3375);
PAINT GREEN (-1177 3375);
DISPLAY INVISIBLE (-1177 3375);
FORCEADD TAP..1
(-1175 3475);
FORCEPROP 3 LASTPIN (-1225 3475) SIG_NAME M_C_CPU1_SA_DQ<17>
J 0
(-1215 3485);
DISPLAY 0.659574 (-1215 3485);
PAINT MONO (-1215 3485);
DISPLAY INVISIBLE (-1215 3485);
FORCEPROP 1 LASTPIN (-1225 3475) BN 17
J 0
(-1237 3483);
DISPLAY 0.680851 (-1237 3483);
PAINT GREEN (-1237 3483);
FORCEPROP 2 LAST CDS_LIB standard
J 0
(-1175 3475);
PAINT MONO (-1175 3475);
DISPLAY INVISIBLE (-1175 3475);
FORCEPROP 1 LAST BODY_TYPE PLUMBING
J 0
(-1175 3525);
DISPLAY 0.872340 (-1175 3525);
PAINT GREEN (-1175 3525);
DISPLAY INVISIBLE (-1175 3525);
FORCEPROP 1 LAST HDL_TAP TRUE
J 0
(-850 3350);
DISPLAY 0.872340 (-850 3350);
DISPLAY INVISIBLE (-850 3350);
FORCEPROP 1 LAST PATH I101
J 0
(-1177 3475);
DISPLAY 0.872340 (-1177 3475);
PAINT GREEN (-1177 3475);
DISPLAY INVISIBLE (-1177 3475);
FORCEADD TAP..1
(-1175 3425);
FORCEPROP 3 LASTPIN (-1225 3425) SIG_NAME M_C_CPU1_SA_DQ<16>
J 0
(-1215 3435);
DISPLAY 0.659574 (-1215 3435);
PAINT MONO (-1215 3435);
DISPLAY INVISIBLE (-1215 3435);
FORCEPROP 1 LASTPIN (-1225 3425) BN 16
J 0
(-1237 3433);
DISPLAY 0.680851 (-1237 3433);
PAINT GREEN (-1237 3433);
FORCEPROP 2 LAST CDS_LIB standard
J 0
(-1175 3425);
PAINT MONO (-1175 3425);
DISPLAY INVISIBLE (-1175 3425);
FORCEPROP 1 LAST BODY_TYPE PLUMBING
J 0
(-1175 3475);
DISPLAY 0.872340 (-1175 3475);
PAINT GREEN (-1175 3475);
DISPLAY INVISIBLE (-1175 3475);
FORCEPROP 1 LAST HDL_TAP TRUE
J 0
(-850 3300);
DISPLAY 0.872340 (-850 3300);
DISPLAY INVISIBLE (-850 3300);
FORCEPROP 1 LAST PATH I102
J 0
(-1177 3425);
DISPLAY 0.872340 (-1177 3425);
PAINT GREEN (-1177 3425);
DISPLAY INVISIBLE (-1177 3425);
FORCEADD TAP..1
(-1175 3575);
FORCEPROP 3 LASTPIN (-1225 3575) SIG_NAME M_C_CPU1_SA_DQ<19>
J 0
(-1215 3585);
DISPLAY 0.659574 (-1215 3585);
PAINT MONO (-1215 3585);
DISPLAY INVISIBLE (-1215 3585);
FORCEPROP 1 LASTPIN (-1225 3575) BN 19
J 0
(-1237 3583);
DISPLAY 0.680851 (-1237 3583);
PAINT GREEN (-1237 3583);
FORCEPROP 2 LAST CDS_LIB standard
J 0
(-1175 3575);
PAINT MONO (-1175 3575);
DISPLAY INVISIBLE (-1175 3575);
FORCEPROP 1 LAST BODY_TYPE PLUMBING
J 0
(-1175 3625);
DISPLAY 0.872340 (-1175 3625);
PAINT GREEN (-1175 3625);
DISPLAY INVISIBLE (-1175 3625);
FORCEPROP 1 LAST HDL_TAP TRUE
J 0
(-850 3450);
DISPLAY 0.872340 (-850 3450);
DISPLAY INVISIBLE (-850 3450);
FORCEPROP 1 LAST PATH I103
J 0
(-1177 3575);
DISPLAY 0.872340 (-1177 3575);
PAINT GREEN (-1177 3575);
DISPLAY INVISIBLE (-1177 3575);
FORCEADD TAP..1
(-1175 3525);
FORCEPROP 3 LASTPIN (-1225 3525) SIG_NAME M_C_CPU1_SA_DQ<18>
J 0
(-1215 3535);
DISPLAY 0.659574 (-1215 3535);
PAINT MONO (-1215 3535);
DISPLAY INVISIBLE (-1215 3535);
FORCEPROP 1 LASTPIN (-1225 3525) BN 18
J 0
(-1237 3533);
DISPLAY 0.680851 (-1237 3533);
PAINT GREEN (-1237 3533);
FORCEPROP 2 LAST CDS_LIB standard
J 0
(-1175 3525);
PAINT MONO (-1175 3525);
DISPLAY INVISIBLE (-1175 3525);
FORCEPROP 1 LAST BODY_TYPE PLUMBING
J 0
(-1175 3575);
DISPLAY 0.872340 (-1175 3575);
PAINT GREEN (-1175 3575);
DISPLAY INVISIBLE (-1175 3575);
FORCEPROP 1 LAST HDL_TAP TRUE
J 0
(-850 3400);
DISPLAY 0.872340 (-850 3400);
DISPLAY INVISIBLE (-850 3400);
FORCEPROP 1 LAST PATH I104
J 0
(-1177 3525);
DISPLAY 0.872340 (-1177 3525);
PAINT GREEN (-1177 3525);
DISPLAY INVISIBLE (-1177 3525);
FORCEADD TAP..1
(-1175 3625);
FORCEPROP 3 LASTPIN (-1225 3625) SIG_NAME M_C_CPU1_SA_DQ<20>
J 0
(-1215 3635);
DISPLAY 0.659574 (-1215 3635);
PAINT MONO (-1215 3635);
DISPLAY INVISIBLE (-1215 3635);
FORCEPROP 1 LASTPIN (-1225 3625) BN 20
J 0
(-1237 3633);
DISPLAY 0.680851 (-1237 3633);
PAINT GREEN (-1237 3633);
FORCEPROP 2 LAST CDS_LIB standard
J 0
(-1175 3625);
PAINT MONO (-1175 3625);
DISPLAY INVISIBLE (-1175 3625);
FORCEPROP 1 LAST BODY_TYPE PLUMBING
J 0
(-1175 3675);
DISPLAY 0.872340 (-1175 3675);
PAINT GREEN (-1175 3675);
DISPLAY INVISIBLE (-1175 3675);
FORCEPROP 1 LAST HDL_TAP TRUE
J 0
(-850 3500);
DISPLAY 0.872340 (-850 3500);
DISPLAY INVISIBLE (-850 3500);
FORCEPROP 1 LAST PATH I105
J 0
(-1177 3625);
DISPLAY 0.872340 (-1177 3625);
PAINT GREEN (-1177 3625);
DISPLAY INVISIBLE (-1177 3625);
FORCEADD TAP..1
(-1175 3725);
FORCEPROP 3 LASTPIN (-1225 3725) SIG_NAME M_C_CPU1_SA_DQ<22>
J 0
(-1215 3735);
DISPLAY 0.659574 (-1215 3735);
PAINT MONO (-1215 3735);
DISPLAY INVISIBLE (-1215 3735);
FORCEPROP 1 LASTPIN (-1225 3725) BN 22
J 0
(-1237 3733);
DISPLAY 0.680851 (-1237 3733);
PAINT GREEN (-1237 3733);
FORCEPROP 2 LAST CDS_LIB standard
J 0
(-1175 3725);
DISPLAY INVISIBLE (-1175 3725);
FORCEPROP 1 LAST BODY_TYPE PLUMBING
J 0
(-1175 3775);
DISPLAY 0.872340 (-1175 3775);
PAINT GREEN (-1175 3775);
DISPLAY INVISIBLE (-1175 3775);
FORCEPROP 1 LAST HDL_TAP TRUE
J 0
(-850 3600);
DISPLAY 0.872340 (-850 3600);
DISPLAY INVISIBLE (-850 3600);
FORCEPROP 1 LAST PATH I106
J 0
(-1177 3725);
DISPLAY 0.872340 (-1177 3725);
PAINT GREEN (-1177 3725);
DISPLAY INVISIBLE (-1177 3725);
FORCEADD TAP..1
(-1175 3675);
FORCEPROP 3 LASTPIN (-1225 3675) SIG_NAME M_C_CPU1_SA_DQ<21>
J 0
(-1215 3685);
DISPLAY 0.659574 (-1215 3685);
PAINT MONO (-1215 3685);
DISPLAY INVISIBLE (-1215 3685);
FORCEPROP 1 LASTPIN (-1225 3675) BN 21
J 0
(-1237 3683);
DISPLAY 0.680851 (-1237 3683);
PAINT GREEN (-1237 3683);
FORCEPROP 2 LAST CDS_LIB standard
J 0
(-1175 3675);
PAINT MONO (-1175 3675);
DISPLAY INVISIBLE (-1175 3675);
FORCEPROP 1 LAST BODY_TYPE PLUMBING
J 0
(-1175 3725);
DISPLAY 0.872340 (-1175 3725);
PAINT GREEN (-1175 3725);
DISPLAY INVISIBLE (-1175 3725);
FORCEPROP 1 LAST HDL_TAP TRUE
J 0
(-850 3550);
DISPLAY 0.872340 (-850 3550);
DISPLAY INVISIBLE (-850 3550);
FORCEPROP 1 LAST PATH I107
J 0
(-1177 3675);
DISPLAY 0.872340 (-1177 3675);
PAINT GREEN (-1177 3675);
DISPLAY INVISIBLE (-1177 3675);
FORCEADD TAP..1
(-1175 3775);
FORCEPROP 3 LASTPIN (-1225 3775) SIG_NAME M_C_CPU1_SA_DQ<23>
J 0
(-1215 3785);
DISPLAY 0.659574 (-1215 3785);
PAINT MONO (-1215 3785);
DISPLAY INVISIBLE (-1215 3785);
FORCEPROP 1 LASTPIN (-1225 3775) BN 23
J 0
(-1237 3783);
DISPLAY 0.680851 (-1237 3783);
PAINT GREEN (-1237 3783);
FORCEPROP 2 LAST CDS_LIB standard
J 0
(-1175 3775);
DISPLAY INVISIBLE (-1175 3775);
FORCEPROP 1 LAST BODY_TYPE PLUMBING
J 0
(-1175 3825);
DISPLAY 0.872340 (-1175 3825);
PAINT GREEN (-1175 3825);
DISPLAY INVISIBLE (-1175 3825);
FORCEPROP 1 LAST HDL_TAP TRUE
J 0
(-850 3650);
DISPLAY 0.872340 (-850 3650);
DISPLAY INVISIBLE (-850 3650);
FORCEPROP 1 LAST PATH I108
J 0
(-1177 3775);
DISPLAY 0.872340 (-1177 3775);
PAINT GREEN (-1177 3775);
DISPLAY INVISIBLE (-1177 3775);
FORCEADD TAP..1
(-1175 3825);
FORCEPROP 3 LASTPIN (-1225 3825) SIG_NAME M_C_CPU1_SA_DQ<24>
J 0
(-1215 3835);
DISPLAY 0.659574 (-1215 3835);
PAINT MONO (-1215 3835);
DISPLAY INVISIBLE (-1215 3835);
FORCEPROP 1 LASTPIN (-1225 3825) BN 24
J 0
(-1237 3833);
DISPLAY 0.680851 (-1237 3833);
PAINT GREEN (-1237 3833);
FORCEPROP 2 LAST CDS_LIB standard
J 0
(-1175 3825);
DISPLAY INVISIBLE (-1175 3825);
FORCEPROP 1 LAST BODY_TYPE PLUMBING
J 0
(-1175 3875);
DISPLAY 0.872340 (-1175 3875);
PAINT GREEN (-1175 3875);
DISPLAY INVISIBLE (-1175 3875);
FORCEPROP 1 LAST HDL_TAP TRUE
J 0
(-850 3700);
DISPLAY 0.872340 (-850 3700);
DISPLAY INVISIBLE (-850 3700);
FORCEPROP 1 LAST PATH I109
J 0
(-1177 3825);
DISPLAY 0.872340 (-1177 3825);
PAINT GREEN (-1177 3825);
DISPLAY INVISIBLE (-1177 3825);
FORCEADD OFFPAGE..1
(-3750 1925);
FORCEPROP 2 LAST $XR3 105 
J 0
(-4122 1889);
DISPLAY 0.638298 (-4122 1889);
PAINT MONO (-4122 1889);
FORCEPROP 2 LAST $XR2 104 
J 0
(-4002 1889);
DISPLAY 0.638298 (-4002 1889);
PAINT MONO (-4002 1889);
FORCEPROP 2 LAST $XR1 103 
J 0
(-4122 1925);
DISPLAY 0.638298 (-4122 1925);
PAINT MONO (-4122 1925);
FORCEPROP 2 LAST $XR0 130 
J 0
(-4002 1925);
DISPLAY 0.638298 (-4002 1925);
PAINT MONO (-4002 1925);
FORCEPROP 2 LAST CDS_LIB standard
J 0
(-3750 1925);
PAINT MONO (-3750 1925);
DISPLAY INVISIBLE (-3750 1925);
FORCEPROP 1 LAST OFFPAGE TRUE
J 0
(-3425 1800);
DISPLAY 0.872340 (-3425 1800);
DISPLAY INVISIBLE (-3425 1800);
FORCEPROP 1 LAST COMMENT_BODY TRUE
J 0
(-3625 1825);
DISPLAY 0.872340 (-3625 1825);
PAINT GREEN (-3625 1825);
DISPLAY INVISIBLE (-3625 1825);
FORCEPROP 2 LAST PATH I11
J 0
(-3700 2000);
DISPLAY 1.021277 (-3700 2000);
DISPLAY INVISIBLE (-3700 2000);
FORCEADD TAP..1
(-1175 3925);
FORCEPROP 3 LASTPIN (-1225 3925) SIG_NAME M_C_CPU1_SA_DQ<26>
J 0
(-1215 3935);
DISPLAY 0.659574 (-1215 3935);
PAINT MONO (-1215 3935);
DISPLAY INVISIBLE (-1215 3935);
FORCEPROP 1 LASTPIN (-1225 3925) BN 26
J 0
(-1237 3933);
DISPLAY 0.680851 (-1237 3933);
PAINT GREEN (-1237 3933);
FORCEPROP 2 LAST CDS_LIB standard
J 0
(-1175 3925);
DISPLAY INVISIBLE (-1175 3925);
FORCEPROP 1 LAST BODY_TYPE PLUMBING
J 0
(-1175 3975);
DISPLAY 0.872340 (-1175 3975);
PAINT GREEN (-1175 3975);
DISPLAY INVISIBLE (-1175 3975);
FORCEPROP 1 LAST HDL_TAP TRUE
J 0
(-850 3800);
DISPLAY 0.872340 (-850 3800);
DISPLAY INVISIBLE (-850 3800);
FORCEPROP 1 LAST PATH I110
J 0
(-1177 3925);
DISPLAY 0.872340 (-1177 3925);
PAINT GREEN (-1177 3925);
DISPLAY INVISIBLE (-1177 3925);
FORCEADD TAP..1
(-1175 3875);
FORCEPROP 3 LASTPIN (-1225 3875) SIG_NAME M_C_CPU1_SA_DQ<25>
J 0
(-1215 3885);
DISPLAY 0.659574 (-1215 3885);
PAINT MONO (-1215 3885);
DISPLAY INVISIBLE (-1215 3885);
FORCEPROP 1 LASTPIN (-1225 3875) BN 25
J 0
(-1237 3883);
DISPLAY 0.680851 (-1237 3883);
PAINT GREEN (-1237 3883);
FORCEPROP 2 LAST CDS_LIB standard
J 0
(-1175 3875);
DISPLAY INVISIBLE (-1175 3875);
FORCEPROP 1 LAST BODY_TYPE PLUMBING
J 0
(-1175 3925);
DISPLAY 0.872340 (-1175 3925);
PAINT GREEN (-1175 3925);
DISPLAY INVISIBLE (-1175 3925);
FORCEPROP 1 LAST HDL_TAP TRUE
J 0
(-850 3750);
DISPLAY 0.872340 (-850 3750);
DISPLAY INVISIBLE (-850 3750);
FORCEPROP 1 LAST PATH I111
J 0
(-1177 3875);
DISPLAY 0.872340 (-1177 3875);
PAINT GREEN (-1177 3875);
DISPLAY INVISIBLE (-1177 3875);
FORCEADD TAP..1
(-1175 3975);
FORCEPROP 3 LASTPIN (-1225 3975) SIG_NAME M_C_CPU1_SA_DQ<27>
J 0
(-1215 3985);
DISPLAY 0.659574 (-1215 3985);
PAINT MONO (-1215 3985);
DISPLAY INVISIBLE (-1215 3985);
FORCEPROP 1 LASTPIN (-1225 3975) BN 27
J 0
(-1237 3983);
DISPLAY 0.680851 (-1237 3983);
PAINT GREEN (-1237 3983);
FORCEPROP 2 LAST CDS_LIB standard
J 0
(-1175 3975);
DISPLAY INVISIBLE (-1175 3975);
FORCEPROP 1 LAST BODY_TYPE PLUMBING
J 0
(-1175 4025);
DISPLAY 0.872340 (-1175 4025);
PAINT GREEN (-1175 4025);
DISPLAY INVISIBLE (-1175 4025);
FORCEPROP 1 LAST HDL_TAP TRUE
J 0
(-850 3850);
DISPLAY 0.872340 (-850 3850);
DISPLAY INVISIBLE (-850 3850);
FORCEPROP 1 LAST PATH I112
J 0
(-1177 3975);
DISPLAY 0.872340 (-1177 3975);
PAINT GREEN (-1177 3975);
DISPLAY INVISIBLE (-1177 3975);
FORCEADD TAP..1
(-1175 4075);
FORCEPROP 3 LASTPIN (-1225 4075) SIG_NAME M_C_CPU1_SA_DQ<29>
J 0
(-1215 4085);
DISPLAY 0.659574 (-1215 4085);
PAINT MONO (-1215 4085);
DISPLAY INVISIBLE (-1215 4085);
FORCEPROP 1 LASTPIN (-1225 4075) BN 29
J 0
(-1237 4083);
DISPLAY 0.680851 (-1237 4083);
PAINT GREEN (-1237 4083);
FORCEPROP 2 LAST CDS_LIB standard
J 0
(-1175 4075);
DISPLAY INVISIBLE (-1175 4075);
FORCEPROP 1 LAST BODY_TYPE PLUMBING
J 0
(-1175 4125);
DISPLAY 0.872340 (-1175 4125);
PAINT GREEN (-1175 4125);
DISPLAY INVISIBLE (-1175 4125);
FORCEPROP 1 LAST HDL_TAP TRUE
J 0
(-850 3950);
DISPLAY 0.872340 (-850 3950);
DISPLAY INVISIBLE (-850 3950);
FORCEPROP 1 LAST PATH I113
J 0
(-1177 4075);
DISPLAY 0.872340 (-1177 4075);
PAINT GREEN (-1177 4075);
DISPLAY INVISIBLE (-1177 4075);
FORCEADD TAP..1
(-1175 4025);
FORCEPROP 3 LASTPIN (-1225 4025) SIG_NAME M_C_CPU1_SA_DQ<28>
J 0
(-1215 4035);
DISPLAY 0.659574 (-1215 4035);
PAINT MONO (-1215 4035);
DISPLAY INVISIBLE (-1215 4035);
FORCEPROP 1 LASTPIN (-1225 4025) BN 28
J 0
(-1237 4033);
DISPLAY 0.680851 (-1237 4033);
PAINT GREEN (-1237 4033);
FORCEPROP 2 LAST CDS_LIB standard
J 0
(-1175 4025);
DISPLAY INVISIBLE (-1175 4025);
FORCEPROP 1 LAST BODY_TYPE PLUMBING
J 0
(-1175 4075);
DISPLAY 0.872340 (-1175 4075);
PAINT GREEN (-1175 4075);
DISPLAY INVISIBLE (-1175 4075);
FORCEPROP 1 LAST HDL_TAP TRUE
J 0
(-850 3900);
DISPLAY 0.872340 (-850 3900);
DISPLAY INVISIBLE (-850 3900);
FORCEPROP 1 LAST PATH I114
J 0
(-1177 4025);
DISPLAY 0.872340 (-1177 4025);
PAINT GREEN (-1177 4025);
DISPLAY INVISIBLE (-1177 4025);
FORCEADD OFFPAGE..3
(-350 2550);
FORCEPROP 2 LAST $XR1 103 
J 0
(-46 2550);
DISPLAY 0.638298 (-46 2550);
PAINT MONO (-46 2550);
FORCEPROP 2 LAST $XR0 53 
J 0
(-136 2550);
DISPLAY 0.638298 (-136 2550);
PAINT MONO (-136 2550);
FORCEPROP 2 LAST CDS_LIB standard
J 2
(-350 2550);
DISPLAY INVISIBLE (-350 2550);
FORCEPROP 1 LAST OFFPAGE TRUE
J 0
(-25 2425);
DISPLAY 0.872340 (-25 2425);
DISPLAY INVISIBLE (-25 2425);
FORCEPROP 1 LAST COMMENT_BODY TRUE
J 0
(-400 2450);
DISPLAY 0.872340 (-400 2450);
PAINT GREEN (-400 2450);
DISPLAY INVISIBLE (-400 2450);
FORCEPROP 2 LAST PATH I115
J 0
(-150 2625);
DISPLAY 1.021277 (-150 2625);
DISPLAY INVISIBLE (-150 2625);
FORCEADD OFFPAGE..1
(-3750 4200);
FORCEPROP 2 LAST $XR1 103 
J 0
(-4091 4200);
DISPLAY 0.638298 (-4091 4200);
PAINT MONO (-4091 4200);
FORCEPROP 2 LAST $XR0 53 
J 0
(-3971 4200);
DISPLAY 0.638298 (-3971 4200);
PAINT MONO (-3971 4200);
FORCEPROP 2 LAST CDS_LIB standard
J 0
(-3750 4200);
PAINT MONO (-3750 4200);
DISPLAY INVISIBLE (-3750 4200);
FORCEPROP 1 LAST OFFPAGE TRUE
J 0
(-3425 4075);
DISPLAY 0.872340 (-3425 4075);
DISPLAY INVISIBLE (-3425 4075);
FORCEPROP 1 LAST COMMENT_BODY TRUE
J 0
(-3625 4100);
DISPLAY 0.872340 (-3625 4100);
PAINT GREEN (-3625 4100);
DISPLAY INVISIBLE (-3625 4100);
FORCEPROP 2 LAST PATH I116
J 0
(-3700 4275);
DISPLAY 1.021277 (-3700 4275);
DISPLAY INVISIBLE (-3700 4275);
FORCEADD TAP..1
R 2
(-2825 4175);
FORCEPROP 3 LASTPIN (-2775 4175) SIG_NAME M_C_CPU1_SA_CA<6>
J 0
(-2765 4185);
DISPLAY 0.659574 (-2765 4185);
PAINT MONO (-2765 4185);
DISPLAY INVISIBLE (-2765 4185);
FORCEPROP 1 LASTPIN (-2775 4175) BN 6
J 2
(-2763 4183);
DISPLAY 0.680851 (-2763 4183);
PAINT GREEN (-2763 4183);
FORCEPROP 2 LAST CDS_LIB standard
J 0
(-2825 4175);
DISPLAY INVISIBLE (-2825 4175);
FORCEPROP 1 LAST BODY_TYPE PLUMBING
J 2
(-2825 4225);
DISPLAY 0.872340 (-2825 4225);
PAINT GREEN (-2825 4225);
DISPLAY INVISIBLE (-2825 4225);
FORCEPROP 1 LAST HDL_TAP TRUE
J 2
(-3150 4050);
DISPLAY 0.872340 (-3150 4050);
DISPLAY INVISIBLE (-3150 4050);
FORCEPROP 1 LAST PATH I117
J 2
(-2823 4175);
DISPLAY 0.872340 (-2823 4175);
PAINT GREEN (-2823 4175);
DISPLAY INVISIBLE (-2823 4175);
FORCEADD TAP..1
R 2
(-2825 4125);
FORCEPROP 3 LASTPIN (-2775 4125) SIG_NAME M_C_CPU1_SA_CA<5>
J 0
(-2765 4135);
DISPLAY 0.659574 (-2765 4135);
PAINT MONO (-2765 4135);
DISPLAY INVISIBLE (-2765 4135);
FORCEPROP 1 LASTPIN (-2775 4125) BN 5
J 2
(-2763 4133);
DISPLAY 0.680851 (-2763 4133);
PAINT GREEN (-2763 4133);
FORCEPROP 2 LAST CDS_LIB standard
J 0
(-2825 4125);
DISPLAY INVISIBLE (-2825 4125);
FORCEPROP 1 LAST BODY_TYPE PLUMBING
J 2
(-2825 4175);
DISPLAY 0.872340 (-2825 4175);
PAINT GREEN (-2825 4175);
DISPLAY INVISIBLE (-2825 4175);
FORCEPROP 1 LAST HDL_TAP TRUE
J 2
(-3150 4000);
DISPLAY 0.872340 (-3150 4000);
DISPLAY INVISIBLE (-3150 4000);
FORCEPROP 1 LAST PATH I118
J 2
(-2823 4125);
DISPLAY 0.872340 (-2823 4125);
PAINT GREEN (-2823 4125);
DISPLAY INVISIBLE (-2823 4125);
FORCEADD TAP..1
(-1175 4175);
FORCEPROP 3 LASTPIN (-1225 4175) SIG_NAME M_C_CPU1_SA_DQ<31>
J 0
(-1215 4185);
DISPLAY 0.659574 (-1215 4185);
PAINT MONO (-1215 4185);
DISPLAY INVISIBLE (-1215 4185);
FORCEPROP 1 LASTPIN (-1225 4175) BN 31
J 0
(-1237 4183);
DISPLAY 0.680851 (-1237 4183);
PAINT GREEN (-1237 4183);
FORCEPROP 2 LAST CDS_LIB standard
J 0
(-1175 4175);
DISPLAY INVISIBLE (-1175 4175);
FORCEPROP 1 LAST BODY_TYPE PLUMBING
J 0
(-1175 4225);
DISPLAY 0.872340 (-1175 4225);
PAINT GREEN (-1175 4225);
DISPLAY INVISIBLE (-1175 4225);
FORCEPROP 1 LAST HDL_TAP TRUE
J 0
(-850 4050);
DISPLAY 0.872340 (-850 4050);
DISPLAY INVISIBLE (-850 4050);
FORCEPROP 1 LAST PATH I119
J 0
(-1177 4175);
DISPLAY 0.872340 (-1177 4175);
PAINT GREEN (-1177 4175);
DISPLAY INVISIBLE (-1177 4175);
FORCEADD VCC_CORE..1
(-3650 2050);
FORCEPROP 3 LASTPIN (-3650 2000) SIG_NAME P3V3_AUX\g
J 0
(-3640 2010);
DISPLAY 0.659574 (-3640 2010);
PAINT MONO (-3640 2010);
DISPLAY INVISIBLE (-3640 2010);
FORCEPROP 1 LAST HDL_POWER P3V3_AUX
J 1
(-3650 2100);
DISPLAY 1.148936 (-3650 2100);
PAINT GREEN (-3650 2100);
FORCEPROP 2 LAST CDS_LIB logical_power
J 0
(-3650 2050);
PAINT MONO (-3650 2050);
DISPLAY INVISIBLE (-3650 2050);
FORCEPROP 1 LAST PATH I12
J 0
(-3600 2075);
DISPLAY 0.872340 (-3600 2075);
PAINT AQUA (-3600 2075);
DISPLAY INVISIBLE (-3600 2075);
FORCEADD TAP..1
(-1175 4125);
FORCEPROP 3 LASTPIN (-1225 4125) SIG_NAME M_C_CPU1_SA_DQ<30>
J 0
(-1215 4135);
DISPLAY 0.659574 (-1215 4135);
PAINT MONO (-1215 4135);
DISPLAY INVISIBLE (-1215 4135);
FORCEPROP 1 LASTPIN (-1225 4125) BN 30
J 0
(-1237 4133);
DISPLAY 0.680851 (-1237 4133);
PAINT GREEN (-1237 4133);
FORCEPROP 2 LAST CDS_LIB standard
J 0
(-1175 4125);
DISPLAY INVISIBLE (-1175 4125);
FORCEPROP 1 LAST BODY_TYPE PLUMBING
J 0
(-1175 4175);
DISPLAY 0.872340 (-1175 4175);
PAINT GREEN (-1175 4175);
DISPLAY INVISIBLE (-1175 4175);
FORCEPROP 1 LAST HDL_TAP TRUE
J 0
(-850 4000);
DISPLAY 0.872340 (-850 4000);
DISPLAY INVISIBLE (-850 4000);
FORCEPROP 1 LAST PATH I120
J 0
(-1177 4125);
DISPLAY 0.872340 (-1177 4125);
PAINT GREEN (-1177 4125);
DISPLAY INVISIBLE (-1177 4125);
FORCEADD OFFPAGE..3
(-350 4200);
FORCEPROP 2 LAST $XR1 103 
J 0
(-46 4200);
DISPLAY 0.638298 (-46 4200);
PAINT MONO (-46 4200);
FORCEPROP 2 LAST $XR0 53 
J 0
(-136 4200);
DISPLAY 0.638298 (-136 4200);
PAINT MONO (-136 4200);
FORCEPROP 2 LAST CDS_LIB standard
J 2
(-350 4200);
DISPLAY INVISIBLE (-350 4200);
FORCEPROP 1 LAST OFFPAGE TRUE
J 0
(-25 4075);
DISPLAY 0.872340 (-25 4075);
DISPLAY INVISIBLE (-25 4075);
FORCEPROP 1 LAST COMMENT_BODY TRUE
J 0
(-400 4100);
DISPLAY 0.872340 (-400 4100);
PAINT GREEN (-400 4100);
DISPLAY INVISIBLE (-400 4100);
FORCEPROP 2 LAST PATH I121
J 0
(-150 4275);
DISPLAY 1.021277 (-150 4275);
DISPLAY INVISIBLE (-150 4275);
FORCEADD UNIVERSAL_GND..1
(550 -75);
FORCEPROP 3 LASTPIN (550 -25) SIG_NAME GND\g
J 0
(560 -15);
DISPLAY 0.659574 (560 -15);
PAINT MONO (560 -15);
DISPLAY INVISIBLE (560 -15);
FORCEPROP 1 LAST PATH I122
J 0
(625 -75);
DISPLAY 0.872340 (625 -75);
PAINT AQUA (625 -75);
DISPLAY INVISIBLE (625 -75);
FORCEPROP 1 LAST HDL_POWER GND
J 1
(575 -150);
DISPLAY 0.872340 (575 -150);
PAINT GREEN (575 -150);
DISPLAY INVISIBLE (575 -150);
FORCEPROP 2 LAST CDS_LIB logical_power
J 0
(550 -75);
PAINT MONO (550 -75);
DISPLAY INVISIBLE (550 -75);
FORCEADD UNIVERSAL_GND..1
(2175 -75);
FORCEPROP 3 LASTPIN (2175 -25) SIG_NAME GND\g
J 0
(2185 -15);
DISPLAY 0.659574 (2185 -15);
PAINT MONO (2185 -15);
DISPLAY INVISIBLE (2185 -15);
FORCEPROP 1 LAST PATH I123
J 0
(2250 -75);
DISPLAY 0.872340 (2250 -75);
PAINT AQUA (2250 -75);
DISPLAY INVISIBLE (2250 -75);
FORCEPROP 1 LAST HDL_POWER GND
J 1
(2200 -150);
DISPLAY 0.872340 (2200 -150);
PAINT GREEN (2200 -150);
DISPLAY INVISIBLE (2200 -150);
FORCEPROP 2 LAST CDS_LIB logical_power
J 0
(2175 -75);
PAINT MONO (2175 -75);
DISPLAY INVISIBLE (2175 -75);
FORCEADD Q_CAP..1
(550 300);
FORCEPROP 1 LAST PART_NUMBER CH5221MEB00
J 0
(600 150);
DISPLAY 0.978723 (600 150);
DISPLAY INVISIBLE (600 150);
FORCEPROP 1 LAST VOLTAGE 6.3V
J 0
(600 300);
DISPLAY 0.978723 (600 300);
FORCEPROP 1 LAST VALUE 2.2UF
J 0
(600 350);
DISPLAY 0.978723 (600 350);
FORCEPROP 1 LAST PACK_TYPE C0402
J 0
(600 100);
DISPLAY 0.978723 (600 100);
FORCEPROP 1 LAST MATERIAL X6S
J 0
(600 200);
DISPLAY 0.978723 (600 200);
FORCEPROP 1 LAST TOLERANCE 20%
J 0
(600 250);
DISPLAY 0.978723 (600 250);
FORCEPROP 1 LAST $LOCATION C62
J 0
(600 400);
DISPLAY 0.978723 (600 400);
FORCEPROP 1 LASTPIN (550 400) $PN 1
J 0
(560 380);
DISPLAY 0.787234 (560 380);
FORCEPROP 1 LASTPIN (550 200) $PN 2
J 0
(560 180);
DISPLAY 0.787234 (560 180);
FORCEPROP 2 LAST CDS_LIB pure_quanta
J 0
(550 300);
PAINT MONO (550 300);
DISPLAY INVISIBLE (550 300);
FORCEPROP 1 LAST PATH I124
J 0
(600 450);
DISPLAY 0.978723 (600 450);
PAINT WHITE (600 450);
DISPLAY INVISIBLE (600 450);
FORCEPROP 1 LAST $LOCATION C62
J 0
(600 500);
DISPLAY 1.021277 (600 500);
DISPLAY INVISIBLE (600 500);
FORCEPROP 2 LAST CDS_LOCATION C62
J 0
(600 500);
DISPLAY 1.021277 (600 500);
DISPLAY INVISIBLE (600 500);
FORCEPROP 2 LAST $SEC 1
J 0
(600 500);
DISPLAY 0.680851 (600 500);
PAINT MONO (600 500);
DISPLAY INVISIBLE (600 500);
FORCEPROP 2 LAST CDS_SEC 1
J 0
(600 500);
DISPLAY 1.021277 (600 500);
DISPLAY INVISIBLE (600 500);
FORCEADD VCC_CORE..1
(550 625);
FORCEPROP 3 LASTPIN (550 575) SIG_NAME P3V3_AUX\g
J 0
(560 585);
DISPLAY 0.659574 (560 585);
PAINT MONO (560 585);
DISPLAY INVISIBLE (560 585);
FORCEPROP 1 LAST HDL_POWER P3V3_AUX
J 1
(550 675);
DISPLAY 1.148936 (550 675);
PAINT GREEN (550 675);
FORCEPROP 2 LAST CDS_LIB logical_power
J 0
(550 625);
PAINT MONO (550 625);
DISPLAY INVISIBLE (550 625);
FORCEPROP 1 LAST PATH I125
J 0
(600 650);
DISPLAY 0.872340 (600 650);
PAINT AQUA (600 650);
DISPLAY INVISIBLE (600 650);
FORCEADD Q_CAP..1
(1550 300);
FORCEPROP 1 LAST PART_NUMBER CH6103KEA00
J 0
(1600 150);
DISPLAY 0.978723 (1600 150);
DISPLAY INVISIBLE (1600 150);
FORCEPROP 1 LAST VOLTAGE 16V
J 0
(1600 300);
DISPLAY 0.978723 (1600 300);
FORCEPROP 1 LAST VALUE 10UF
J 0
(1600 350);
DISPLAY 0.978723 (1600 350);
FORCEPROP 1 LAST TOLERANCE 10%
J 0
(1600 250);
DISPLAY 0.978723 (1600 250);
FORCEPROP 1 LAST PACK_TYPE C0805
J 0
(1600 100);
DISPLAY 0.978723 (1600 100);
FORCEPROP 1 LAST MATERIAL X6S
J 0
(1600 200);
DISPLAY 0.978723 (1600 200);
FORCEPROP 1 LAST $LOCATION C63
J 0
(1600 400);
DISPLAY 0.978723 (1600 400);
FORCEPROP 1 LASTPIN (1550 400) $PN 1
J 0
(1560 380);
DISPLAY 0.787234 (1560 380);
FORCEPROP 1 LASTPIN (1550 200) $PN 2
J 0
(1560 180);
DISPLAY 0.787234 (1560 180);
FORCEPROP 2 LAST CDS_LIB pure_quanta
J 0
(1550 300);
PAINT MONO (1550 300);
DISPLAY INVISIBLE (1550 300);
FORCEPROP 1 LAST PATH I127
J 0
(1600 450);
DISPLAY 0.978723 (1600 450);
PAINT WHITE (1600 450);
DISPLAY INVISIBLE (1600 450);
FORCEPROP 1 LAST $LOCATION C63
J 0
(1600 500);
DISPLAY 1.021277 (1600 500);
DISPLAY INVISIBLE (1600 500);
FORCEPROP 2 LAST CDS_LOCATION C63
J 0
(1600 500);
DISPLAY 1.021277 (1600 500);
DISPLAY INVISIBLE (1600 500);
FORCEPROP 2 LAST $SEC 1
J 0
(1600 500);
DISPLAY 0.680851 (1600 500);
PAINT MONO (1600 500);
DISPLAY INVISIBLE (1600 500);
FORCEPROP 2 LAST CDS_SEC 1
J 0
(1600 500);
DISPLAY 1.021277 (1600 500);
DISPLAY INVISIBLE (1600 500);
FORCEADD VCC_CORE..1
(1550 625);
FORCEPROP 3 LASTPIN (1550 575) SIG_NAME P12V_S3_AUX_CPU1_NVDIMM\g
J 0
(1560 585);
DISPLAY 0.659574 (1560 585);
PAINT MONO (1560 585);
DISPLAY INVISIBLE (1560 585);
FORCEPROP 1 LAST HDL_POWER P12V_S3_AUX_CPU1_NVDIMM
J 1
(1550 675);
DISPLAY 1.148936 (1550 675);
PAINT GREEN (1550 675);
FORCEPROP 2 LAST CDS_LIB logical_power
J 0
(1550 625);
PAINT MONO (1550 625);
DISPLAY INVISIBLE (1550 625);
FORCEPROP 1 LAST PATH I128
J 0
(1600 650);
DISPLAY 0.872340 (1600 650);
PAINT AQUA (1600 650);
DISPLAY INVISIBLE (1600 650);
FORCEADD TAP..1
(1575 2325);
FORCEPROP 3 LASTPIN (1525 2325) SIG_NAME M_C_CPU1_SB_DQS_DP<1>
J 0
(1535 2335);
DISPLAY 0.659574 (1535 2335);
PAINT MONO (1535 2335);
DISPLAY INVISIBLE (1535 2335);
FORCEPROP 1 LASTPIN (1525 2325) BN 1
J 0
(1513 2333);
DISPLAY 0.680851 (1513 2333);
PAINT GREEN (1513 2333);
FORCEPROP 2 LAST CDS_LIB standard
J 0
(1575 2325);
DISPLAY INVISIBLE (1575 2325);
FORCEPROP 1 LAST BODY_TYPE PLUMBING
J 0
(1575 2375);
DISPLAY 0.872340 (1575 2375);
PAINT GREEN (1575 2375);
DISPLAY INVISIBLE (1575 2375);
FORCEPROP 1 LAST HDL_TAP TRUE
J 0
(1900 2200);
DISPLAY 0.872340 (1900 2200);
DISPLAY INVISIBLE (1900 2200);
FORCEPROP 1 LAST PATH I129
J 0
(1573 2325);
DISPLAY 0.872340 (1573 2325);
PAINT GREEN (1573 2325);
DISPLAY INVISIBLE (1573 2325);
FORCEADD SCONN288_ADR50017P130CC..1
(-2000 2450);
FORCEPROP 1 LAST PART_NUMBER DFHST8FS461
J 0
(-2445 4472);
DISPLAY 0.723404 (-2445 4472);
PAINT GREEN (-2445 4472);
DISPLAY INVISIBLE (-2445 4472);
FORCEPROP 1 LAST MATERIAL IO
J 0
(-2445 4345);
DISPLAY 0.723404 (-2445 4345);
PAINT GREEN (-2445 4345);
FORCEPROP 2 LAST VALUE SCONN288_ADR50017-P130CC
J 0
(-2450 4575);
DISPLAY 1.021277 (-2450 4575);
FORCEPROP 2 LAST PART_TYPE SMLF
J 0
(-2450 4625);
DISPLAY 1.021277 (-2450 4625);
FORCEPROP 1 LAST $LOCATION J21
J 0
(-2450 4525);
DISPLAY 0.723404 (-2450 4525);
PAINT GREEN (-2450 4525);
FORCEPROP 0 LASTPIN (-2600 1825) $PN 62
J 2
(-2610 1835);
DISPLAY 0.680851 (-2610 1835);
PAINT MONO (-2610 1835);
FORCEPROP 0 LASTPIN (-2600 3875) $PN 66
J 2
(-2610 3885);
DISPLAY 0.680851 (-2610 3885);
PAINT MONO (-2610 3885);
FORCEPROP 0 LASTPIN (-2600 3475) $PN 76
J 2
(-2610 3485);
DISPLAY 0.680851 (-2610 3485);
PAINT MONO (-2610 3485);
FORCEPROP 0 LASTPIN (-2600 3925) $PN 211
J 2
(-2610 3935);
DISPLAY 0.680851 (-2610 3935);
PAINT MONO (-2610 3935);
FORCEPROP 0 LASTPIN (-2600 3525) $PN 221
J 2
(-2610 3535);
DISPLAY 0.680851 (-2610 3535);
PAINT MONO (-2610 3535);
FORCEPROP 0 LASTPIN (-2600 3975) $PN 68
J 2
(-2610 3985);
DISPLAY 0.680851 (-2610 3985);
PAINT MONO (-2610 3985);
FORCEPROP 0 LASTPIN (-2600 3575) $PN 78
J 2
(-2610 3585);
DISPLAY 0.680851 (-2610 3585);
PAINT MONO (-2610 3585);
FORCEPROP 0 LASTPIN (-2600 4025) $PN 213
J 2
(-2610 4035);
DISPLAY 0.680851 (-2610 4035);
PAINT MONO (-2610 4035);
FORCEPROP 0 LASTPIN (-2600 3625) $PN 223
J 2
(-2610 3635);
DISPLAY 0.680851 (-2610 3635);
PAINT MONO (-2610 3635);
FORCEPROP 0 LASTPIN (-2600 4075) $PN 70
J 2
(-2610 4085);
DISPLAY 0.680851 (-2610 4085);
PAINT MONO (-2610 4085);
FORCEPROP 0 LASTPIN (-2600 3675) $PN 80
J 2
(-2610 3685);
DISPLAY 0.680851 (-2610 3685);
PAINT MONO (-2610 3685);
FORCEPROP 0 LASTPIN (-2600 4125) $PN 215
J 2
(-2610 4135);
DISPLAY 0.680851 (-2610 4135);
PAINT MONO (-2610 4135);
FORCEPROP 0 LASTPIN (-2600 3725) $PN 225
J 2
(-2610 3735);
DISPLAY 0.680851 (-2610 3735);
PAINT MONO (-2610 3735);
FORCEPROP 0 LASTPIN (-2600 4175) $PN 72
J 2
(-2610 4185);
DISPLAY 0.680851 (-2610 4185);
PAINT MONO (-2610 4185);
FORCEPROP 0 LASTPIN (-2600 3775) $PN 82
J 2
(-2610 3785);
DISPLAY 0.680851 (-2610 3785);
PAINT MONO (-2610 3785);
FORCEPROP 0 LASTPIN (-2600 2425) $PN 51
J 2
(-2610 2435);
DISPLAY 0.680851 (-2610 2435);
PAINT MONO (-2610 2435);
FORCEPROP 0 LASTPIN (-2600 1975) $PN 96
J 2
(-2610 1985);
DISPLAY 0.680851 (-2610 1985);
PAINT MONO (-2610 1985);
FORCEPROP 0 LASTPIN (-2600 2475) $PN 53
J 2
(-2610 2485);
DISPLAY 0.680851 (-2610 2485);
PAINT MONO (-2610 2485);
FORCEPROP 0 LASTPIN (-2600 2025) $PN 98
J 2
(-2610 2035);
DISPLAY 0.680851 (-2610 2035);
PAINT MONO (-2610 2035);
FORCEPROP 0 LASTPIN (-2600 2525) $PN 196
J 2
(-2610 2535);
DISPLAY 0.680851 (-2610 2535);
PAINT MONO (-2610 2535);
FORCEPROP 0 LASTPIN (-2600 2075) $PN 241
J 2
(-2610 2085);
DISPLAY 0.680851 (-2610 2085);
PAINT MONO (-2610 2085);
FORCEPROP 0 LASTPIN (-2600 2575) $PN 198
J 2
(-2610 2585);
DISPLAY 0.680851 (-2610 2585);
PAINT MONO (-2610 2585);
FORCEPROP 0 LASTPIN (-2600 2125) $PN 243
J 2
(-2610 2135);
DISPLAY 0.680851 (-2610 2135);
PAINT MONO (-2610 2135);
FORCEPROP 0 LASTPIN (-2600 2625) $PN 58
J 2
(-2610 2635);
DISPLAY 0.680851 (-2610 2635);
PAINT MONO (-2610 2635);
FORCEPROP 0 LASTPIN (-2600 2175) $PN 89
J 2
(-2610 2185);
DISPLAY 0.680851 (-2610 2185);
PAINT MONO (-2610 2185);
FORCEPROP 0 LASTPIN (-2600 2675) $PN 60
J 2
(-2610 2685);
DISPLAY 0.680851 (-2610 2685);
PAINT MONO (-2610 2685);
FORCEPROP 0 LASTPIN (-2600 2225) $PN 91
J 2
(-2610 2235);
DISPLAY 0.680851 (-2610 2235);
PAINT MONO (-2610 2235);
FORCEPROP 0 LASTPIN (-2600 2725) $PN 203
J 2
(-2610 2735);
DISPLAY 0.680851 (-2610 2735);
PAINT MONO (-2610 2735);
FORCEPROP 0 LASTPIN (-2600 2275) $PN 234
J 2
(-2610 2285);
DISPLAY 0.680851 (-2610 2285);
PAINT MONO (-2610 2285);
FORCEPROP 0 LASTPIN (-2600 2775) $PN 205
J 2
(-2610 2785);
DISPLAY 0.680851 (-2610 2785);
PAINT MONO (-2610 2785);
FORCEPROP 0 LASTPIN (-2600 2325) $PN 236
J 2
(-2610 2335);
DISPLAY 0.680851 (-2610 2335);
PAINT MONO (-2610 2335);
FORCEPROP 0 LASTPIN (-2600 2875) $PN 218
J 2
(-2610 2885);
DISPLAY 0.680851 (-2610 2885);
PAINT MONO (-2610 2885);
FORCEPROP 0 LASTPIN (-2600 2925) $PN 217
J 2
(-2610 2935);
DISPLAY 0.680851 (-2610 2935);
PAINT MONO (-2610 2935);
FORCEPROP 0 LASTPIN (-2600 3175) $PN 64
J 2
(-2610 3185);
DISPLAY 0.680851 (-2610 3185);
PAINT MONO (-2610 3185);
FORCEPROP 0 LASTPIN (-2600 3025) $PN 84
J 2
(-2610 3035);
DISPLAY 0.680851 (-2610 3035);
PAINT MONO (-2610 3035);
FORCEPROP 0 LASTPIN (-2600 3225) $PN 209
J 2
(-2610 3235);
DISPLAY 0.680851 (-2610 3235);
PAINT MONO (-2610 3235);
FORCEPROP 0 LASTPIN (-2600 3075) $PN 229
J 2
(-2610 3085);
DISPLAY 0.680851 (-2610 3085);
PAINT MONO (-2610 3085);
FORCEPROP 0 LASTPIN (-1400 2625) $PN 7
J 0
(-1390 2635);
DISPLAY 0.680851 (-1390 2635);
PAINT MONO (-1390 2635);
FORCEPROP 0 LASTPIN (-1400 975) $PN 100
J 0
(-1390 985);
DISPLAY 0.680851 (-1390 985);
PAINT MONO (-1390 985);
FORCEPROP 0 LASTPIN (-1400 2675) $PN 9
J 0
(-1390 2685);
DISPLAY 0.680851 (-1390 2685);
PAINT MONO (-1390 2685);
FORCEPROP 0 LASTPIN (-1400 1025) $PN 102
J 0
(-1390 1035);
DISPLAY 0.680851 (-1390 1035);
PAINT MONO (-1390 1035);
FORCEPROP 0 LASTPIN (-1400 2725) $PN 152
J 0
(-1390 2735);
DISPLAY 0.680851 (-1390 2735);
PAINT MONO (-1390 2735);
FORCEPROP 0 LASTPIN (-1400 1075) $PN 245
J 0
(-1390 1085);
DISPLAY 0.680851 (-1390 1085);
PAINT MONO (-1390 1085);
FORCEPROP 0 LASTPIN (-1400 2775) $PN 154
J 0
(-1390 2785);
DISPLAY 0.680851 (-1390 2785);
PAINT MONO (-1390 2785);
FORCEPROP 0 LASTPIN (-1400 1125) $PN 247
J 0
(-1390 1135);
DISPLAY 0.680851 (-1390 1135);
PAINT MONO (-1390 1135);
FORCEPROP 0 LASTPIN (-1400 2825) $PN 14
J 0
(-1390 2835);
DISPLAY 0.680851 (-1390 2835);
PAINT MONO (-1390 2835);
FORCEPROP 0 LASTPIN (-1400 1175) $PN 107
J 0
(-1390 1185);
DISPLAY 0.680851 (-1390 1185);
PAINT MONO (-1390 1185);
FORCEPROP 0 LASTPIN (-1400 2875) $PN 16
J 0
(-1390 2885);
DISPLAY 0.680851 (-1390 2885);
PAINT MONO (-1390 2885);
FORCEPROP 0 LASTPIN (-1400 1225) $PN 109
J 0
(-1390 1235);
DISPLAY 0.680851 (-1390 1235);
PAINT MONO (-1390 1235);
FORCEPROP 0 LASTPIN (-1400 2925) $PN 159
J 0
(-1390 2935);
DISPLAY 0.680851 (-1390 2935);
PAINT MONO (-1390 2935);
FORCEPROP 0 LASTPIN (-1400 1275) $PN 252
J 0
(-1390 1285);
DISPLAY 0.680851 (-1390 1285);
PAINT MONO (-1390 1285);
FORCEPROP 0 LASTPIN (-1400 2975) $PN 161
J 0
(-1390 2985);
DISPLAY 0.680851 (-1390 2985);
PAINT MONO (-1390 2985);
FORCEPROP 0 LASTPIN (-1400 1325) $PN 254
J 0
(-1390 1335);
DISPLAY 0.680851 (-1390 1335);
PAINT MONO (-1390 1335);
FORCEPROP 0 LASTPIN (-1400 3025) $PN 18
J 0
(-1390 3035);
DISPLAY 0.680851 (-1390 3035);
PAINT MONO (-1390 3035);
FORCEPROP 0 LASTPIN (-1400 1375) $PN 111
J 0
(-1390 1385);
DISPLAY 0.680851 (-1390 1385);
PAINT MONO (-1390 1385);
FORCEPROP 0 LASTPIN (-1400 3075) $PN 20
J 0
(-1390 3085);
DISPLAY 0.680851 (-1390 3085);
PAINT MONO (-1390 3085);
FORCEPROP 0 LASTPIN (-1400 1425) $PN 113
J 0
(-1390 1435);
DISPLAY 0.680851 (-1390 1435);
PAINT MONO (-1390 1435);
FORCEPROP 0 LASTPIN (-1400 3125) $PN 163
J 0
(-1390 3135);
DISPLAY 0.680851 (-1390 3135);
PAINT MONO (-1390 3135);
FORCEPROP 0 LASTPIN (-1400 1475) $PN 256
J 0
(-1390 1485);
DISPLAY 0.680851 (-1390 1485);
PAINT MONO (-1390 1485);
FORCEPROP 0 LASTPIN (-1400 3175) $PN 165
J 0
(-1390 3185);
DISPLAY 0.680851 (-1390 3185);
PAINT MONO (-1390 3185);
FORCEPROP 0 LASTPIN (-1400 1525) $PN 258
J 0
(-1390 1535);
DISPLAY 0.680851 (-1390 1535);
PAINT MONO (-1390 1535);
FORCEPROP 0 LASTPIN (-1400 3225) $PN 25
J 0
(-1390 3235);
DISPLAY 0.680851 (-1390 3235);
PAINT MONO (-1390 3235);
FORCEPROP 0 LASTPIN (-1400 1575) $PN 118
J 0
(-1390 1585);
DISPLAY 0.680851 (-1390 1585);
PAINT MONO (-1390 1585);
FORCEPROP 0 LASTPIN (-1400 3275) $PN 27
J 0
(-1390 3285);
DISPLAY 0.680851 (-1390 3285);
PAINT MONO (-1390 3285);
FORCEPROP 0 LASTPIN (-1400 1625) $PN 120
J 0
(-1390 1635);
DISPLAY 0.680851 (-1390 1635);
PAINT MONO (-1390 1635);
FORCEPROP 0 LASTPIN (-1400 3325) $PN 170
J 0
(-1390 3335);
DISPLAY 0.680851 (-1390 3335);
PAINT MONO (-1390 3335);
FORCEPROP 0 LASTPIN (-1400 1675) $PN 263
J 0
(-1390 1685);
DISPLAY 0.680851 (-1390 1685);
PAINT MONO (-1390 1685);
FORCEPROP 0 LASTPIN (-1400 3375) $PN 172
J 0
(-1390 3385);
DISPLAY 0.680851 (-1390 3385);
PAINT MONO (-1390 3385);
FORCEPROP 0 LASTPIN (-1400 1725) $PN 265
J 0
(-1390 1735);
DISPLAY 0.680851 (-1390 1735);
PAINT MONO (-1390 1735);
FORCEPROP 0 LASTPIN (-1400 3425) $PN 29
J 0
(-1390 3435);
DISPLAY 0.680851 (-1390 3435);
PAINT MONO (-1390 3435);
FORCEPROP 0 LASTPIN (-1400 1775) $PN 122
J 0
(-1390 1785);
DISPLAY 0.680851 (-1390 1785);
PAINT MONO (-1390 1785);
FORCEPROP 0 LASTPIN (-1400 3475) $PN 31
J 0
(-1390 3485);
DISPLAY 0.680851 (-1390 3485);
PAINT MONO (-1390 3485);
FORCEPROP 0 LASTPIN (-1400 1825) $PN 124
J 0
(-1390 1835);
DISPLAY 0.680851 (-1390 1835);
PAINT MONO (-1390 1835);
FORCEPROP 0 LASTPIN (-1400 3525) $PN 174
J 0
(-1390 3535);
DISPLAY 0.680851 (-1390 3535);
PAINT MONO (-1390 3535);
FORCEPROP 0 LASTPIN (-1400 1875) $PN 267
J 0
(-1390 1885);
DISPLAY 0.680851 (-1390 1885);
PAINT MONO (-1390 1885);
FORCEPROP 0 LASTPIN (-1400 3575) $PN 176
J 0
(-1390 3585);
DISPLAY 0.680851 (-1390 3585);
PAINT MONO (-1390 3585);
FORCEPROP 0 LASTPIN (-1400 1925) $PN 269
J 0
(-1390 1935);
DISPLAY 0.680851 (-1390 1935);
PAINT MONO (-1390 1935);
FORCEPROP 0 LASTPIN (-1400 3625) $PN 36
J 0
(-1390 3635);
DISPLAY 0.680851 (-1390 3635);
PAINT MONO (-1390 3635);
FORCEPROP 0 LASTPIN (-1400 1975) $PN 129
J 0
(-1390 1985);
DISPLAY 0.680851 (-1390 1985);
PAINT MONO (-1390 1985);
FORCEPROP 0 LASTPIN (-1400 3675) $PN 38
J 0
(-1390 3685);
DISPLAY 0.680851 (-1390 3685);
PAINT MONO (-1390 3685);
FORCEPROP 0 LASTPIN (-1400 2025) $PN 131
J 0
(-1390 2035);
DISPLAY 0.680851 (-1390 2035);
PAINT MONO (-1390 2035);
FORCEPROP 0 LASTPIN (-1400 3725) $PN 181
J 0
(-1390 3735);
DISPLAY 0.680851 (-1390 3735);
PAINT MONO (-1390 3735);
FORCEPROP 0 LASTPIN (-1400 2075) $PN 274
J 0
(-1390 2085);
DISPLAY 0.680851 (-1390 2085);
PAINT MONO (-1390 2085);
FORCEPROP 0 LASTPIN (-1400 3775) $PN 183
J 0
(-1390 3785);
DISPLAY 0.680851 (-1390 3785);
PAINT MONO (-1390 3785);
FORCEPROP 0 LASTPIN (-1400 2125) $PN 276
J 0
(-1390 2135);
DISPLAY 0.680851 (-1390 2135);
PAINT MONO (-1390 2135);
FORCEPROP 0 LASTPIN (-1400 3825) $PN 40
J 0
(-1390 3835);
DISPLAY 0.680851 (-1390 3835);
PAINT MONO (-1390 3835);
FORCEPROP 0 LASTPIN (-1400 2175) $PN 133
J 0
(-1390 2185);
DISPLAY 0.680851 (-1390 2185);
PAINT MONO (-1390 2185);
FORCEPROP 0 LASTPIN (-1400 3875) $PN 42
J 0
(-1390 3885);
DISPLAY 0.680851 (-1390 3885);
PAINT MONO (-1390 3885);
FORCEPROP 0 LASTPIN (-1400 2225) $PN 135
J 0
(-1390 2235);
DISPLAY 0.680851 (-1390 2235);
PAINT MONO (-1390 2235);
FORCEPROP 0 LASTPIN (-1400 3925) $PN 185
J 0
(-1390 3935);
DISPLAY 0.680851 (-1390 3935);
PAINT MONO (-1390 3935);
FORCEPROP 0 LASTPIN (-1400 2275) $PN 278
J 0
(-1390 2285);
DISPLAY 0.680851 (-1390 2285);
PAINT MONO (-1390 2285);
FORCEPROP 0 LASTPIN (-1400 3975) $PN 187
J 0
(-1390 3985);
DISPLAY 0.680851 (-1390 3985);
PAINT MONO (-1390 3985);
FORCEPROP 0 LASTPIN (-1400 2325) $PN 280
J 0
(-1390 2335);
DISPLAY 0.680851 (-1390 2335);
PAINT MONO (-1390 2335);
FORCEPROP 0 LASTPIN (-1400 4025) $PN 47
J 0
(-1390 4035);
DISPLAY 0.680851 (-1390 4035);
PAINT MONO (-1390 4035);
FORCEPROP 0 LASTPIN (-1400 2375) $PN 140
J 0
(-1390 2385);
DISPLAY 0.680851 (-1390 2385);
PAINT MONO (-1390 2385);
FORCEPROP 0 LASTPIN (-1400 4075) $PN 49
J 0
(-1390 4085);
DISPLAY 0.680851 (-1390 4085);
PAINT MONO (-1390 4085);
FORCEPROP 0 LASTPIN (-1400 2425) $PN 142
J 0
(-1390 2435);
DISPLAY 0.680851 (-1390 2435);
PAINT MONO (-1390 2435);
FORCEPROP 0 LASTPIN (-1400 4125) $PN 192
J 0
(-1390 4135);
DISPLAY 0.680851 (-1390 4135);
PAINT MONO (-1390 4135);
FORCEPROP 0 LASTPIN (-1400 2475) $PN 285
J 0
(-1390 2485);
DISPLAY 0.680851 (-1390 2485);
PAINT MONO (-1390 2485);
FORCEPROP 0 LASTPIN (-1400 4175) $PN 194
J 0
(-1390 4185);
DISPLAY 0.680851 (-1390 4185);
PAINT MONO (-1390 4185);
FORCEPROP 0 LASTPIN (-1400 2525) $PN 287
J 0
(-1390 2535);
DISPLAY 0.680851 (-1390 2535);
PAINT MONO (-1390 2535);
FORCEPROP 0 LASTPIN (-2600 1675) $PN 148
J 2
(-2610 1685);
DISPLAY 0.680851 (-2610 1685);
PAINT MONO (-2610 1685);
FORCEPROP 0 LASTPIN (-2600 1575) $PN 4
J 2
(-2610 1585);
DISPLAY 0.680851 (-2610 1585);
PAINT MONO (-2610 1585);
FORCEPROP 0 LASTPIN (-2600 1625) $PN 5
J 2
(-2610 1635);
DISPLAY 0.680851 (-2610 1635);
PAINT MONO (-2610 1635);
FORCEPROP 0 LASTPIN (-2600 775) $PN 86
J 2
(-2610 785);
DISPLAY 0.680851 (-2610 785);
PAINT MONO (-2610 785);
FORCEPROP 0 LASTPIN (-2600 725) $PN 87
J 2
(-2610 735);
DISPLAY 0.680851 (-2610 735);
PAINT MONO (-2610 735);
FORCEPROP 0 LASTPIN (-2600 3375) $PN 74
J 2
(-2610 3385);
DISPLAY 0.680851 (-2610 3385);
PAINT MONO (-2610 3385);
FORCEPROP 0 LASTPIN (-2600 3325) $PN 227
J 2
(-2610 3335);
DISPLAY 0.680851 (-2610 3335);
PAINT MONO (-2610 3335);
FORCEPROP 0 LASTPIN (-2600 1325) $PN 147
J 2
(-2610 1335);
DISPLAY 0.680851 (-2610 1335);
PAINT MONO (-2610 1335);
FORCEPROP 0 LASTPIN (-2600 1875) $PN 207
J 2
(-2610 1885);
DISPLAY 0.680851 (-2610 1885);
PAINT MONO (-2610 1885);
FORCEPROP 0 LASTPIN (-2600 925) $PN 2
J 2
(-2610 935);
DISPLAY 0.680851 (-2610 935);
PAINT MONO (-2610 935);
FORCEPROP 0 LASTPIN (-2600 975) $PN 144
J 2
(-2610 985);
DISPLAY 0.680851 (-2610 985);
PAINT MONO (-2610 985);
FORCEPROP 0 LASTPIN (-2600 1025) $PN 149
J 2
(-2610 1035);
DISPLAY 0.680851 (-2610 1035);
PAINT MONO (-2610 1035);
FORCEPROP 0 LASTPIN (-2600 1075) $PN 150
J 2
(-2610 1085);
DISPLAY 0.680851 (-2610 1085);
PAINT MONO (-2610 1085);
FORCEPROP 0 LASTPIN (-2600 1125) $PN 220
J 2
(-2610 1135);
DISPLAY 0.680851 (-2610 1135);
PAINT MONO (-2610 1135);
FORCEPROP 0 LASTPIN (-2600 1175) $PN 231
J 2
(-2610 1185);
DISPLAY 0.680851 (-2610 1185);
PAINT MONO (-2610 1185);
FORCEPROP 0 LASTPIN (-2600 1225) $PN 232
J 2
(-2610 1235);
DISPLAY 0.680851 (-2610 1235);
PAINT MONO (-2610 1235);
FORCEPROP 0 LASTPIN (-2600 1725) $PN 3
J 2
(-2610 1735);
DISPLAY 0.680851 (-2610 1735);
PAINT MONO (-2610 1735);
FORCEPROP 1 LAST NEEDS_NO_SIZE TRUE
J 0
(-2000 2450);
DISPLAY 0.723404 (-2000 2450);
PAINT GREEN (-2000 2450);
DISPLAY INVISIBLE (-2000 2450);
FORCEPROP 1 LAST CDS_LMAN_SYM_OUTLINE -450,1875,450,-1875
J 0
(-2000 2450);
DISPLAY 0.468085 (-2000 2450);
PAINT GREEN (-2000 2450);
DISPLAY INVISIBLE (-2000 2450);
FORCEPROP 2 LAST CDS_LIB pure_quanta
J 0
(-2000 2450);
DISPLAY INVISIBLE (-2000 2450);
FORCEPROP 1 LAST PATH I13
J 0
(-2000 2450);
DISPLAY 0.723404 (-2000 2450);
PAINT GREEN (-2000 2450);
DISPLAY INVISIBLE (-2000 2450);
FORCEPROP 2 LAST CDS_LOCATION J21
J 0
(-2450 4675);
DISPLAY 1.021277 (-2450 4675);
DISPLAY INVISIBLE (-2450 4675);
FORCEPROP 0 LAST $SEC 1
J 0
(-2425 4675);
DISPLAY 0.680851 (-2425 4675);
PAINT MONO (-2425 4675);
DISPLAY INVISIBLE (-2425 4675);
FORCEPROP 2 LAST CDS_SEC 1
J 0
(-2450 4675);
DISPLAY 1.021277 (-2450 4675);
DISPLAY INVISIBLE (-2450 4675);
FORCEADD TAP..1
(1575 2225);
FORCEPROP 3 LASTPIN (1525 2225) SIG_NAME M_C_CPU1_SB_DQS_DP<0>
J 0
(1535 2235);
DISPLAY 0.659574 (1535 2235);
PAINT MONO (1535 2235);
DISPLAY INVISIBLE (1535 2235);
FORCEPROP 1 LASTPIN (1525 2225) BN 0
J 0
(1513 2233);
DISPLAY 0.680851 (1513 2233);
PAINT GREEN (1513 2233);
FORCEPROP 2 LAST CDS_LIB standard
J 0
(1575 2225);
PAINT MONO (1575 2225);
DISPLAY INVISIBLE (1575 2225);
FORCEPROP 1 LAST BODY_TYPE PLUMBING
J 0
(1575 2275);
DISPLAY 0.872340 (1575 2275);
PAINT GREEN (1575 2275);
DISPLAY INVISIBLE (1575 2275);
FORCEPROP 1 LAST HDL_TAP TRUE
J 0
(1900 2100);
DISPLAY 0.872340 (1900 2100);
DISPLAY INVISIBLE (1900 2100);
FORCEPROP 1 LAST PATH I130
J 0
(1573 2225);
DISPLAY 0.872340 (1573 2225);
PAINT GREEN (1573 2225);
DISPLAY INVISIBLE (1573 2225);
FORCEADD TAP..1
(1575 2425);
FORCEPROP 3 LASTPIN (1525 2425) SIG_NAME M_C_CPU1_SB_DQS_DP<2>
J 0
(1535 2435);
DISPLAY 0.659574 (1535 2435);
PAINT MONO (1535 2435);
DISPLAY INVISIBLE (1535 2435);
FORCEPROP 1 LASTPIN (1525 2425) BN 2
J 0
(1513 2433);
DISPLAY 0.680851 (1513 2433);
PAINT GREEN (1513 2433);
FORCEPROP 2 LAST CDS_LIB standard
J 0
(1575 2425);
DISPLAY INVISIBLE (1575 2425);
FORCEPROP 1 LAST BODY_TYPE PLUMBING
J 0
(1575 2475);
DISPLAY 0.872340 (1575 2475);
PAINT GREEN (1575 2475);
DISPLAY INVISIBLE (1575 2475);
FORCEPROP 1 LAST HDL_TAP TRUE
J 0
(1900 2300);
DISPLAY 0.872340 (1900 2300);
DISPLAY INVISIBLE (1900 2300);
FORCEPROP 1 LAST PATH I131
J 0
(1573 2425);
DISPLAY 0.872340 (1573 2425);
PAINT GREEN (1573 2425);
DISPLAY INVISIBLE (1573 2425);
FORCEADD TAP..1
(1575 2525);
FORCEPROP 3 LASTPIN (1525 2525) SIG_NAME M_C_CPU1_SB_DQS_DP<3>
J 0
(1535 2535);
DISPLAY 0.659574 (1535 2535);
PAINT MONO (1535 2535);
DISPLAY INVISIBLE (1535 2535);
FORCEPROP 1 LASTPIN (1525 2525) BN 3
J 0
(1513 2533);
DISPLAY 0.680851 (1513 2533);
PAINT GREEN (1513 2533);
FORCEPROP 2 LAST CDS_LIB standard
J 0
(1575 2525);
PAINT MONO (1575 2525);
DISPLAY INVISIBLE (1575 2525);
FORCEPROP 1 LAST BODY_TYPE PLUMBING
J 0
(1575 2575);
DISPLAY 0.872340 (1575 2575);
PAINT GREEN (1575 2575);
DISPLAY INVISIBLE (1575 2575);
FORCEPROP 1 LAST HDL_TAP TRUE
J 0
(1900 2400);
DISPLAY 0.872340 (1900 2400);
DISPLAY INVISIBLE (1900 2400);
FORCEPROP 1 LAST PATH I132
J 0
(1573 2525);
DISPLAY 0.872340 (1573 2525);
PAINT GREEN (1573 2525);
DISPLAY INVISIBLE (1573 2525);
FORCEADD TAP..1
(1575 2625);
FORCEPROP 3 LASTPIN (1525 2625) SIG_NAME M_C_CPU1_SB_DQS_DP<4>
J 0
(1535 2635);
DISPLAY 0.659574 (1535 2635);
PAINT MONO (1535 2635);
DISPLAY INVISIBLE (1535 2635);
FORCEPROP 1 LASTPIN (1525 2625) BN 4
J 0
(1513 2633);
DISPLAY 0.680851 (1513 2633);
PAINT GREEN (1513 2633);
FORCEPROP 2 LAST CDS_LIB standard
J 0
(1575 2625);
PAINT MONO (1575 2625);
DISPLAY INVISIBLE (1575 2625);
FORCEPROP 1 LAST BODY_TYPE PLUMBING
J 0
(1575 2675);
DISPLAY 0.872340 (1575 2675);
PAINT GREEN (1575 2675);
DISPLAY INVISIBLE (1575 2675);
FORCEPROP 1 LAST HDL_TAP TRUE
J 0
(1900 2500);
DISPLAY 0.872340 (1900 2500);
DISPLAY INVISIBLE (1900 2500);
FORCEPROP 1 LAST PATH I133
J 0
(1573 2625);
DISPLAY 0.872340 (1573 2625);
PAINT GREEN (1573 2625);
DISPLAY INVISIBLE (1573 2625);
FORCEADD TAP..1
(1575 2825);
FORCEPROP 3 LASTPIN (1525 2825) SIG_NAME M_C_CPU1_SB_DQS_DP<6>
J 0
(1535 2835);
DISPLAY 0.659574 (1535 2835);
PAINT MONO (1535 2835);
DISPLAY INVISIBLE (1535 2835);
FORCEPROP 1 LASTPIN (1525 2825) BN 6
J 0
(1513 2833);
DISPLAY 0.680851 (1513 2833);
PAINT GREEN (1513 2833);
FORCEPROP 2 LAST CDS_LIB standard
J 0
(1575 2825);
DISPLAY INVISIBLE (1575 2825);
FORCEPROP 1 LAST BODY_TYPE PLUMBING
J 0
(1575 2875);
DISPLAY 0.872340 (1575 2875);
PAINT GREEN (1575 2875);
DISPLAY INVISIBLE (1575 2875);
FORCEPROP 1 LAST HDL_TAP TRUE
J 0
(1900 2700);
DISPLAY 0.872340 (1900 2700);
DISPLAY INVISIBLE (1900 2700);
FORCEPROP 1 LAST PATH I134
J 0
(1573 2825);
DISPLAY 0.872340 (1573 2825);
PAINT GREEN (1573 2825);
DISPLAY INVISIBLE (1573 2825);
FORCEADD TAP..1
(1575 2725);
FORCEPROP 3 LASTPIN (1525 2725) SIG_NAME M_C_CPU1_SB_DQS_DP<5>
J 0
(1535 2735);
DISPLAY 0.659574 (1535 2735);
PAINT MONO (1535 2735);
DISPLAY INVISIBLE (1535 2735);
FORCEPROP 1 LASTPIN (1525 2725) BN 5
J 0
(1513 2733);
DISPLAY 0.680851 (1513 2733);
PAINT GREEN (1513 2733);
FORCEPROP 2 LAST CDS_LIB standard
J 0
(1575 2725);
DISPLAY INVISIBLE (1575 2725);
FORCEPROP 1 LAST BODY_TYPE PLUMBING
J 0
(1575 2775);
DISPLAY 0.872340 (1575 2775);
PAINT GREEN (1575 2775);
DISPLAY INVISIBLE (1575 2775);
FORCEPROP 1 LAST HDL_TAP TRUE
J 0
(1900 2600);
DISPLAY 0.872340 (1900 2600);
DISPLAY INVISIBLE (1900 2600);
FORCEPROP 1 LAST PATH I135
J 0
(1573 2725);
DISPLAY 0.872340 (1573 2725);
PAINT GREEN (1573 2725);
DISPLAY INVISIBLE (1573 2725);
FORCEADD TAP..1
(1575 2925);
FORCEPROP 3 LASTPIN (1525 2925) SIG_NAME M_C_CPU1_SB_DQS_DP<7>
J 0
(1535 2935);
DISPLAY 0.659574 (1535 2935);
PAINT MONO (1535 2935);
DISPLAY INVISIBLE (1535 2935);
FORCEPROP 1 LASTPIN (1525 2925) BN 7
J 0
(1513 2933);
DISPLAY 0.680851 (1513 2933);
PAINT GREEN (1513 2933);
FORCEPROP 2 LAST CDS_LIB standard
J 0
(1575 2925);
DISPLAY INVISIBLE (1575 2925);
FORCEPROP 1 LAST BODY_TYPE PLUMBING
J 0
(1575 2975);
DISPLAY 0.872340 (1575 2975);
PAINT GREEN (1575 2975);
DISPLAY INVISIBLE (1575 2975);
FORCEPROP 1 LAST HDL_TAP TRUE
J 0
(1900 2800);
DISPLAY 0.872340 (1900 2800);
DISPLAY INVISIBLE (1900 2800);
FORCEPROP 1 LAST PATH I136
J 0
(1573 2925);
DISPLAY 0.872340 (1573 2925);
PAINT GREEN (1573 2925);
DISPLAY INVISIBLE (1573 2925);
FORCEADD TAP..1
(1575 3025);
FORCEPROP 3 LASTPIN (1525 3025) SIG_NAME M_C_CPU1_SB_DQS_DP<8>
J 0
(1535 3035);
DISPLAY 0.659574 (1535 3035);
PAINT MONO (1535 3035);
DISPLAY INVISIBLE (1535 3035);
FORCEPROP 1 LASTPIN (1525 3025) BN 8
J 0
(1513 3033);
DISPLAY 0.680851 (1513 3033);
PAINT GREEN (1513 3033);
FORCEPROP 2 LAST CDS_LIB standard
J 0
(1575 3025);
DISPLAY INVISIBLE (1575 3025);
FORCEPROP 1 LAST BODY_TYPE PLUMBING
J 0
(1575 3075);
DISPLAY 0.872340 (1575 3075);
PAINT GREEN (1575 3075);
DISPLAY INVISIBLE (1575 3075);
FORCEPROP 1 LAST HDL_TAP TRUE
J 0
(1900 2900);
DISPLAY 0.872340 (1900 2900);
DISPLAY INVISIBLE (1900 2900);
FORCEPROP 1 LAST PATH I137
J 0
(1573 3025);
DISPLAY 0.872340 (1573 3025);
PAINT GREEN (1573 3025);
DISPLAY INVISIBLE (1573 3025);
FORCEADD TAP..1
(1750 2175);
FORCEPROP 3 LASTPIN (1700 2175) SIG_NAME M_C_CPU1_SB_DQS_DN<0>
J 0
(1710 2185);
DISPLAY 0.659574 (1710 2185);
PAINT MONO (1710 2185);
DISPLAY INVISIBLE (1710 2185);
FORCEPROP 1 LASTPIN (1700 2175) BN 0
J 0
(1688 2183);
DISPLAY 0.680851 (1688 2183);
PAINT GREEN (1688 2183);
FORCEPROP 2 LAST CDS_LIB standard
J 0
(1750 2175);
PAINT MONO (1750 2175);
DISPLAY INVISIBLE (1750 2175);
FORCEPROP 1 LAST BODY_TYPE PLUMBING
J 0
(1750 2225);
DISPLAY 0.872340 (1750 2225);
PAINT GREEN (1750 2225);
DISPLAY INVISIBLE (1750 2225);
FORCEPROP 1 LAST HDL_TAP TRUE
J 0
(2075 2050);
DISPLAY 0.872340 (2075 2050);
DISPLAY INVISIBLE (2075 2050);
FORCEPROP 1 LAST PATH I138
J 0
(1748 2175);
DISPLAY 0.872340 (1748 2175);
PAINT GREEN (1748 2175);
DISPLAY INVISIBLE (1748 2175);
FORCEADD TAP..1
(1750 2275);
FORCEPROP 3 LASTPIN (1700 2275) SIG_NAME M_C_CPU1_SB_DQS_DN<1>
J 0
(1710 2285);
DISPLAY 0.659574 (1710 2285);
PAINT MONO (1710 2285);
DISPLAY INVISIBLE (1710 2285);
FORCEPROP 1 LASTPIN (1700 2275) BN 1
J 0
(1688 2283);
DISPLAY 0.680851 (1688 2283);
PAINT GREEN (1688 2283);
FORCEPROP 2 LAST CDS_LIB standard
J 0
(1750 2275);
DISPLAY INVISIBLE (1750 2275);
FORCEPROP 1 LAST BODY_TYPE PLUMBING
J 0
(1750 2325);
DISPLAY 0.872340 (1750 2325);
PAINT GREEN (1750 2325);
DISPLAY INVISIBLE (1750 2325);
FORCEPROP 1 LAST HDL_TAP TRUE
J 0
(2075 2150);
DISPLAY 0.872340 (2075 2150);
DISPLAY INVISIBLE (2075 2150);
FORCEPROP 1 LAST PATH I139
J 0
(1748 2275);
DISPLAY 0.872340 (1748 2275);
PAINT GREEN (1748 2275);
DISPLAY INVISIBLE (1748 2275);
FORCEADD TAP..1
R 2
(-2825 1975);
FORCEPROP 3 LASTPIN (-2775 1975) SIG_NAME M_C_CPU1_SB_CB<0>
J 0
(-2765 1985);
DISPLAY 0.659574 (-2765 1985);
PAINT MONO (-2765 1985);
DISPLAY INVISIBLE (-2765 1985);
FORCEPROP 1 LASTPIN (-2775 1975) BN 0
J 2
(-2763 1983);
DISPLAY 0.680851 (-2763 1983);
PAINT GREEN (-2763 1983);
FORCEPROP 2 LAST CDS_LIB standard
J 0
(-2825 1975);
PAINT MONO (-2825 1975);
DISPLAY INVISIBLE (-2825 1975);
FORCEPROP 1 LAST BODY_TYPE PLUMBING
J 2
(-2825 2025);
DISPLAY 0.872340 (-2825 2025);
PAINT GREEN (-2825 2025);
DISPLAY INVISIBLE (-2825 2025);
FORCEPROP 1 LAST HDL_TAP TRUE
J 2
(-3150 1850);
DISPLAY 0.872340 (-3150 1850);
DISPLAY INVISIBLE (-3150 1850);
FORCEPROP 1 LAST PATH I14
J 2
(-2823 1975);
DISPLAY 0.872340 (-2823 1975);
PAINT GREEN (-2823 1975);
DISPLAY INVISIBLE (-2823 1975);
FORCEADD TAP..1
(1750 2375);
FORCEPROP 3 LASTPIN (1700 2375) SIG_NAME M_C_CPU1_SB_DQS_DN<2>
J 0
(1710 2385);
DISPLAY 0.659574 (1710 2385);
PAINT MONO (1710 2385);
DISPLAY INVISIBLE (1710 2385);
FORCEPROP 1 LASTPIN (1700 2375) BN 2
J 0
(1688 2383);
DISPLAY 0.680851 (1688 2383);
PAINT GREEN (1688 2383);
FORCEPROP 2 LAST CDS_LIB standard
J 0
(1750 2375);
DISPLAY INVISIBLE (1750 2375);
FORCEPROP 1 LAST BODY_TYPE PLUMBING
J 0
(1750 2425);
DISPLAY 0.872340 (1750 2425);
PAINT GREEN (1750 2425);
DISPLAY INVISIBLE (1750 2425);
FORCEPROP 1 LAST HDL_TAP TRUE
J 0
(2075 2250);
DISPLAY 0.872340 (2075 2250);
DISPLAY INVISIBLE (2075 2250);
FORCEPROP 1 LAST PATH I140
J 0
(1748 2375);
DISPLAY 0.872340 (1748 2375);
PAINT GREEN (1748 2375);
DISPLAY INVISIBLE (1748 2375);
FORCEADD TAP..1
(1750 2475);
FORCEPROP 3 LASTPIN (1700 2475) SIG_NAME M_C_CPU1_SB_DQS_DN<3>
J 0
(1710 2485);
DISPLAY 0.659574 (1710 2485);
PAINT MONO (1710 2485);
DISPLAY INVISIBLE (1710 2485);
FORCEPROP 1 LASTPIN (1700 2475) BN 3
J 0
(1688 2483);
DISPLAY 0.680851 (1688 2483);
PAINT GREEN (1688 2483);
FORCEPROP 2 LAST CDS_LIB standard
J 0
(1750 2475);
PAINT MONO (1750 2475);
DISPLAY INVISIBLE (1750 2475);
FORCEPROP 1 LAST BODY_TYPE PLUMBING
J 0
(1750 2525);
DISPLAY 0.872340 (1750 2525);
PAINT GREEN (1750 2525);
DISPLAY INVISIBLE (1750 2525);
FORCEPROP 1 LAST HDL_TAP TRUE
J 0
(2075 2350);
DISPLAY 0.872340 (2075 2350);
DISPLAY INVISIBLE (2075 2350);
FORCEPROP 1 LAST PATH I141
J 0
(1748 2475);
DISPLAY 0.872340 (1748 2475);
PAINT GREEN (1748 2475);
DISPLAY INVISIBLE (1748 2475);
FORCEADD TAP..1
(1750 2575);
FORCEPROP 3 LASTPIN (1700 2575) SIG_NAME M_C_CPU1_SB_DQS_DN<4>
J 0
(1710 2585);
DISPLAY 0.659574 (1710 2585);
PAINT MONO (1710 2585);
DISPLAY INVISIBLE (1710 2585);
FORCEPROP 1 LASTPIN (1700 2575) BN 4
J 0
(1688 2583);
DISPLAY 0.680851 (1688 2583);
PAINT GREEN (1688 2583);
FORCEPROP 2 LAST CDS_LIB standard
J 0
(1750 2575);
PAINT MONO (1750 2575);
DISPLAY INVISIBLE (1750 2575);
FORCEPROP 1 LAST BODY_TYPE PLUMBING
J 0
(1750 2625);
DISPLAY 0.872340 (1750 2625);
PAINT GREEN (1750 2625);
DISPLAY INVISIBLE (1750 2625);
FORCEPROP 1 LAST HDL_TAP TRUE
J 0
(2075 2450);
DISPLAY 0.872340 (2075 2450);
DISPLAY INVISIBLE (2075 2450);
FORCEPROP 1 LAST PATH I142
J 0
(1748 2575);
DISPLAY 0.872340 (1748 2575);
PAINT GREEN (1748 2575);
DISPLAY INVISIBLE (1748 2575);
FORCEADD TAP..1
(1750 2675);
FORCEPROP 3 LASTPIN (1700 2675) SIG_NAME M_C_CPU1_SB_DQS_DN<5>
J 0
(1710 2685);
DISPLAY 0.659574 (1710 2685);
PAINT MONO (1710 2685);
DISPLAY INVISIBLE (1710 2685);
FORCEPROP 1 LASTPIN (1700 2675) BN 5
J 0
(1688 2683);
DISPLAY 0.680851 (1688 2683);
PAINT GREEN (1688 2683);
FORCEPROP 2 LAST CDS_LIB standard
J 0
(1750 2675);
DISPLAY INVISIBLE (1750 2675);
FORCEPROP 1 LAST BODY_TYPE PLUMBING
J 0
(1750 2725);
DISPLAY 0.872340 (1750 2725);
PAINT GREEN (1750 2725);
DISPLAY INVISIBLE (1750 2725);
FORCEPROP 1 LAST HDL_TAP TRUE
J 0
(2075 2550);
DISPLAY 0.872340 (2075 2550);
DISPLAY INVISIBLE (2075 2550);
FORCEPROP 1 LAST PATH I143
J 0
(1748 2675);
DISPLAY 0.872340 (1748 2675);
PAINT GREEN (1748 2675);
DISPLAY INVISIBLE (1748 2675);
FORCEADD TAP..1
(1750 2775);
FORCEPROP 3 LASTPIN (1700 2775) SIG_NAME M_C_CPU1_SB_DQS_DN<6>
J 0
(1710 2785);
DISPLAY 0.659574 (1710 2785);
PAINT MONO (1710 2785);
DISPLAY INVISIBLE (1710 2785);
FORCEPROP 1 LASTPIN (1700 2775) BN 6
J 0
(1688 2783);
DISPLAY 0.680851 (1688 2783);
PAINT GREEN (1688 2783);
FORCEPROP 2 LAST CDS_LIB standard
J 0
(1750 2775);
DISPLAY INVISIBLE (1750 2775);
FORCEPROP 1 LAST BODY_TYPE PLUMBING
J 0
(1750 2825);
DISPLAY 0.872340 (1750 2825);
PAINT GREEN (1750 2825);
DISPLAY INVISIBLE (1750 2825);
FORCEPROP 1 LAST HDL_TAP TRUE
J 0
(2075 2650);
DISPLAY 0.872340 (2075 2650);
DISPLAY INVISIBLE (2075 2650);
FORCEPROP 1 LAST PATH I144
J 0
(1748 2775);
DISPLAY 0.872340 (1748 2775);
PAINT GREEN (1748 2775);
DISPLAY INVISIBLE (1748 2775);
FORCEADD TAP..1
(1750 2875);
FORCEPROP 3 LASTPIN (1700 2875) SIG_NAME M_C_CPU1_SB_DQS_DN<7>
J 0
(1710 2885);
DISPLAY 0.659574 (1710 2885);
PAINT MONO (1710 2885);
DISPLAY INVISIBLE (1710 2885);
FORCEPROP 1 LASTPIN (1700 2875) BN 7
J 0
(1688 2883);
DISPLAY 0.680851 (1688 2883);
PAINT GREEN (1688 2883);
FORCEPROP 2 LAST CDS_LIB standard
J 0
(1750 2875);
DISPLAY INVISIBLE (1750 2875);
FORCEPROP 1 LAST BODY_TYPE PLUMBING
J 0
(1750 2925);
DISPLAY 0.872340 (1750 2925);
PAINT GREEN (1750 2925);
DISPLAY INVISIBLE (1750 2925);
FORCEPROP 1 LAST HDL_TAP TRUE
J 0
(2075 2750);
DISPLAY 0.872340 (2075 2750);
DISPLAY INVISIBLE (2075 2750);
FORCEPROP 1 LAST PATH I145
J 0
(1748 2875);
DISPLAY 0.872340 (1748 2875);
PAINT GREEN (1748 2875);
DISPLAY INVISIBLE (1748 2875);
FORCEADD TAP..1
(1750 3075);
FORCEPROP 3 LASTPIN (1700 3075) SIG_NAME M_C_CPU1_SB_DQS_DN<9>
J 0
(1710 3085);
DISPLAY 0.659574 (1710 3085);
PAINT MONO (1710 3085);
DISPLAY INVISIBLE (1710 3085);
FORCEPROP 1 LASTPIN (1700 3075) BN 9
J 0
(1688 3083);
DISPLAY 0.680851 (1688 3083);
PAINT GREEN (1688 3083);
FORCEPROP 2 LAST CDS_LIB standard
J 0
(1750 3075);
DISPLAY INVISIBLE (1750 3075);
FORCEPROP 1 LAST BODY_TYPE PLUMBING
J 0
(1750 3125);
DISPLAY 0.872340 (1750 3125);
PAINT GREEN (1750 3125);
DISPLAY INVISIBLE (1750 3125);
FORCEPROP 1 LAST HDL_TAP TRUE
J 0
(2075 2950);
DISPLAY 0.872340 (2075 2950);
DISPLAY INVISIBLE (2075 2950);
FORCEPROP 1 LAST PATH I146
J 0
(1748 3075);
DISPLAY 0.872340 (1748 3075);
PAINT GREEN (1748 3075);
DISPLAY INVISIBLE (1748 3075);
FORCEADD TAP..1
(1750 2975);
FORCEPROP 3 LASTPIN (1700 2975) SIG_NAME M_C_CPU1_SB_DQS_DN<8>
J 0
(1710 2985);
DISPLAY 0.659574 (1710 2985);
PAINT MONO (1710 2985);
DISPLAY INVISIBLE (1710 2985);
FORCEPROP 1 LASTPIN (1700 2975) BN 8
J 0
(1688 2983);
DISPLAY 0.680851 (1688 2983);
PAINT GREEN (1688 2983);
FORCEPROP 2 LAST CDS_LIB standard
J 0
(1750 2975);
DISPLAY INVISIBLE (1750 2975);
FORCEPROP 1 LAST BODY_TYPE PLUMBING
J 0
(1750 3025);
DISPLAY 0.872340 (1750 3025);
PAINT GREEN (1750 3025);
DISPLAY INVISIBLE (1750 3025);
FORCEPROP 1 LAST HDL_TAP TRUE
J 0
(2075 2850);
DISPLAY 0.872340 (2075 2850);
DISPLAY INVISIBLE (2075 2850);
FORCEPROP 1 LAST PATH I147
J 0
(1748 2975);
DISPLAY 0.872340 (1748 2975);
PAINT GREEN (1748 2975);
DISPLAY INVISIBLE (1748 2975);
FORCEADD TAP..1
(1575 3125);
FORCEPROP 3 LASTPIN (1525 3125) SIG_NAME M_C_CPU1_SB_DQS_DP<9>
J 0
(1535 3135);
DISPLAY 0.659574 (1535 3135);
PAINT MONO (1535 3135);
DISPLAY INVISIBLE (1535 3135);
FORCEPROP 1 LASTPIN (1525 3125) BN 9
J 0
(1513 3133);
DISPLAY 0.680851 (1513 3133);
PAINT GREEN (1513 3133);
FORCEPROP 2 LAST CDS_LIB standard
J 0
(1575 3125);
DISPLAY INVISIBLE (1575 3125);
FORCEPROP 1 LAST BODY_TYPE PLUMBING
J 0
(1575 3175);
DISPLAY 0.872340 (1575 3175);
PAINT GREEN (1575 3175);
DISPLAY INVISIBLE (1575 3175);
FORCEPROP 1 LAST HDL_TAP TRUE
J 0
(1900 3000);
DISPLAY 0.872340 (1900 3000);
DISPLAY INVISIBLE (1900 3000);
FORCEPROP 1 LAST PATH I148
J 0
(1573 3125);
DISPLAY 0.872340 (1573 3125);
PAINT GREEN (1573 3125);
DISPLAY INVISIBLE (1573 3125);
FORCEADD TAP..1
(1575 3275);
FORCEPROP 3 LASTPIN (1525 3275) SIG_NAME M_C_CPU1_SA_DQS_DP<0>
J 0
(1535 3285);
DISPLAY 0.659574 (1535 3285);
PAINT MONO (1535 3285);
DISPLAY INVISIBLE (1535 3285);
FORCEPROP 1 LASTPIN (1525 3275) BN 0
J 0
(1513 3283);
DISPLAY 0.680851 (1513 3283);
PAINT GREEN (1513 3283);
FORCEPROP 2 LAST CDS_LIB standard
J 0
(1575 3275);
PAINT MONO (1575 3275);
DISPLAY INVISIBLE (1575 3275);
FORCEPROP 1 LAST BODY_TYPE PLUMBING
J 0
(1575 3325);
DISPLAY 0.872340 (1575 3325);
PAINT GREEN (1575 3325);
DISPLAY INVISIBLE (1575 3325);
FORCEPROP 1 LAST HDL_TAP TRUE
J 0
(1900 3150);
DISPLAY 0.872340 (1900 3150);
DISPLAY INVISIBLE (1900 3150);
FORCEPROP 1 LAST PATH I149
J 0
(1573 3275);
DISPLAY 0.872340 (1573 3275);
PAINT GREEN (1573 3275);
DISPLAY INVISIBLE (1573 3275);
FORCEADD TAP..1
R 2
(-2825 2025);
FORCEPROP 3 LASTPIN (-2775 2025) SIG_NAME M_C_CPU1_SB_CB<1>
J 0
(-2765 2035);
DISPLAY 0.659574 (-2765 2035);
PAINT MONO (-2765 2035);
DISPLAY INVISIBLE (-2765 2035);
FORCEPROP 1 LASTPIN (-2775 2025) BN 1
J 2
(-2763 2033);
DISPLAY 0.680851 (-2763 2033);
PAINT GREEN (-2763 2033);
FORCEPROP 2 LAST CDS_LIB standard
J 0
(-2825 2025);
DISPLAY INVISIBLE (-2825 2025);
FORCEPROP 1 LAST BODY_TYPE PLUMBING
J 2
(-2825 2075);
DISPLAY 0.872340 (-2825 2075);
PAINT GREEN (-2825 2075);
DISPLAY INVISIBLE (-2825 2075);
FORCEPROP 1 LAST HDL_TAP TRUE
J 2
(-3150 1900);
DISPLAY 0.872340 (-3150 1900);
DISPLAY INVISIBLE (-3150 1900);
FORCEPROP 1 LAST PATH I15
J 2
(-2823 2025);
DISPLAY 0.872340 (-2823 2025);
PAINT GREEN (-2823 2025);
DISPLAY INVISIBLE (-2823 2025);
FORCEADD TAP..1
(1575 3475);
FORCEPROP 3 LASTPIN (1525 3475) SIG_NAME M_C_CPU1_SA_DQS_DP<2>
J 0
(1535 3485);
DISPLAY 0.659574 (1535 3485);
PAINT MONO (1535 3485);
DISPLAY INVISIBLE (1535 3485);
FORCEPROP 1 LASTPIN (1525 3475) BN 2
J 0
(1513 3483);
DISPLAY 0.680851 (1513 3483);
PAINT GREEN (1513 3483);
FORCEPROP 2 LAST CDS_LIB standard
J 0
(1575 3475);
DISPLAY INVISIBLE (1575 3475);
FORCEPROP 1 LAST BODY_TYPE PLUMBING
J 0
(1575 3525);
DISPLAY 0.872340 (1575 3525);
PAINT GREEN (1575 3525);
DISPLAY INVISIBLE (1575 3525);
FORCEPROP 1 LAST HDL_TAP TRUE
J 0
(1900 3350);
DISPLAY 0.872340 (1900 3350);
DISPLAY INVISIBLE (1900 3350);
FORCEPROP 1 LAST PATH I150
J 0
(1573 3475);
DISPLAY 0.872340 (1573 3475);
PAINT GREEN (1573 3475);
DISPLAY INVISIBLE (1573 3475);
FORCEADD TAP..1
(1575 3375);
FORCEPROP 3 LASTPIN (1525 3375) SIG_NAME M_C_CPU1_SA_DQS_DP<1>
J 0
(1535 3385);
DISPLAY 0.659574 (1535 3385);
PAINT MONO (1535 3385);
DISPLAY INVISIBLE (1535 3385);
FORCEPROP 1 LASTPIN (1525 3375) BN 1
J 0
(1513 3383);
DISPLAY 0.680851 (1513 3383);
PAINT GREEN (1513 3383);
FORCEPROP 2 LAST CDS_LIB standard
J 0
(1575 3375);
DISPLAY INVISIBLE (1575 3375);
FORCEPROP 1 LAST BODY_TYPE PLUMBING
J 0
(1575 3425);
DISPLAY 0.872340 (1575 3425);
PAINT GREEN (1575 3425);
DISPLAY INVISIBLE (1575 3425);
FORCEPROP 1 LAST HDL_TAP TRUE
J 0
(1900 3250);
DISPLAY 0.872340 (1900 3250);
DISPLAY INVISIBLE (1900 3250);
FORCEPROP 1 LAST PATH I151
J 0
(1573 3375);
DISPLAY 0.872340 (1573 3375);
PAINT GREEN (1573 3375);
DISPLAY INVISIBLE (1573 3375);
FORCEADD TAP..1
(1575 3575);
FORCEPROP 3 LASTPIN (1525 3575) SIG_NAME M_C_CPU1_SA_DQS_DP<3>
J 0
(1535 3585);
DISPLAY 0.659574 (1535 3585);
PAINT MONO (1535 3585);
DISPLAY INVISIBLE (1535 3585);
FORCEPROP 1 LASTPIN (1525 3575) BN 3
J 0
(1513 3583);
DISPLAY 0.680851 (1513 3583);
PAINT GREEN (1513 3583);
FORCEPROP 2 LAST CDS_LIB standard
J 0
(1575 3575);
PAINT MONO (1575 3575);
DISPLAY INVISIBLE (1575 3575);
FORCEPROP 1 LAST BODY_TYPE PLUMBING
J 0
(1575 3625);
DISPLAY 0.872340 (1575 3625);
PAINT GREEN (1575 3625);
DISPLAY INVISIBLE (1575 3625);
FORCEPROP 1 LAST HDL_TAP TRUE
J 0
(1900 3450);
DISPLAY 0.872340 (1900 3450);
DISPLAY INVISIBLE (1900 3450);
FORCEPROP 1 LAST PATH I152
J 0
(1573 3575);
DISPLAY 0.872340 (1573 3575);
PAINT GREEN (1573 3575);
DISPLAY INVISIBLE (1573 3575);
FORCEADD TAP..1
(1575 3675);
FORCEPROP 3 LASTPIN (1525 3675) SIG_NAME M_C_CPU1_SA_DQS_DP<4>
J 0
(1535 3685);
DISPLAY 0.659574 (1535 3685);
PAINT MONO (1535 3685);
DISPLAY INVISIBLE (1535 3685);
FORCEPROP 1 LASTPIN (1525 3675) BN 4
J 0
(1513 3683);
DISPLAY 0.680851 (1513 3683);
PAINT GREEN (1513 3683);
FORCEPROP 2 LAST CDS_LIB standard
J 0
(1575 3675);
PAINT MONO (1575 3675);
DISPLAY INVISIBLE (1575 3675);
FORCEPROP 1 LAST BODY_TYPE PLUMBING
J 0
(1575 3725);
DISPLAY 0.872340 (1575 3725);
PAINT GREEN (1575 3725);
DISPLAY INVISIBLE (1575 3725);
FORCEPROP 1 LAST HDL_TAP TRUE
J 0
(1900 3550);
DISPLAY 0.872340 (1900 3550);
DISPLAY INVISIBLE (1900 3550);
FORCEPROP 1 LAST PATH I153
J 0
(1573 3675);
DISPLAY 0.872340 (1573 3675);
PAINT GREEN (1573 3675);
DISPLAY INVISIBLE (1573 3675);
FORCEADD TAP..1
(1575 3775);
FORCEPROP 3 LASTPIN (1525 3775) SIG_NAME M_C_CPU1_SA_DQS_DP<5>
J 0
(1535 3785);
DISPLAY 0.659574 (1535 3785);
PAINT MONO (1535 3785);
DISPLAY INVISIBLE (1535 3785);
FORCEPROP 1 LASTPIN (1525 3775) BN 5
J 0
(1513 3783);
DISPLAY 0.680851 (1513 3783);
PAINT GREEN (1513 3783);
FORCEPROP 2 LAST CDS_LIB standard
J 0
(1575 3775);
DISPLAY INVISIBLE (1575 3775);
FORCEPROP 1 LAST BODY_TYPE PLUMBING
J 0
(1575 3825);
DISPLAY 0.872340 (1575 3825);
PAINT GREEN (1575 3825);
DISPLAY INVISIBLE (1575 3825);
FORCEPROP 1 LAST HDL_TAP TRUE
J 0
(1900 3650);
DISPLAY 0.872340 (1900 3650);
DISPLAY INVISIBLE (1900 3650);
FORCEPROP 1 LAST PATH I154
J 0
(1573 3775);
DISPLAY 0.872340 (1573 3775);
PAINT GREEN (1573 3775);
DISPLAY INVISIBLE (1573 3775);
FORCEADD TAP..1
(1575 3875);
FORCEPROP 3 LASTPIN (1525 3875) SIG_NAME M_C_CPU1_SA_DQS_DP<6>
J 0
(1535 3885);
DISPLAY 0.659574 (1535 3885);
PAINT MONO (1535 3885);
DISPLAY INVISIBLE (1535 3885);
FORCEPROP 1 LASTPIN (1525 3875) BN 6
J 0
(1513 3883);
DISPLAY 0.680851 (1513 3883);
PAINT GREEN (1513 3883);
FORCEPROP 2 LAST CDS_LIB standard
J 0
(1575 3875);
DISPLAY INVISIBLE (1575 3875);
FORCEPROP 1 LAST BODY_TYPE PLUMBING
J 0
(1575 3925);
DISPLAY 0.872340 (1575 3925);
PAINT GREEN (1575 3925);
DISPLAY INVISIBLE (1575 3925);
FORCEPROP 1 LAST HDL_TAP TRUE
J 0
(1900 3750);
DISPLAY 0.872340 (1900 3750);
DISPLAY INVISIBLE (1900 3750);
FORCEPROP 1 LAST PATH I155
J 0
(1573 3875);
DISPLAY 0.872340 (1573 3875);
PAINT GREEN (1573 3875);
DISPLAY INVISIBLE (1573 3875);
FORCEADD TAP..1
(1575 3975);
FORCEPROP 3 LASTPIN (1525 3975) SIG_NAME M_C_CPU1_SA_DQS_DP<7>
J 0
(1535 3985);
DISPLAY 0.659574 (1535 3985);
PAINT MONO (1535 3985);
DISPLAY INVISIBLE (1535 3985);
FORCEPROP 1 LASTPIN (1525 3975) BN 7
J 0
(1513 3983);
DISPLAY 0.680851 (1513 3983);
PAINT GREEN (1513 3983);
FORCEPROP 2 LAST CDS_LIB standard
J 0
(1575 3975);
DISPLAY INVISIBLE (1575 3975);
FORCEPROP 1 LAST BODY_TYPE PLUMBING
J 0
(1575 4025);
DISPLAY 0.872340 (1575 4025);
PAINT GREEN (1575 4025);
DISPLAY INVISIBLE (1575 4025);
FORCEPROP 1 LAST HDL_TAP TRUE
J 0
(1900 3850);
DISPLAY 0.872340 (1900 3850);
DISPLAY INVISIBLE (1900 3850);
FORCEPROP 1 LAST PATH I156
J 0
(1573 3975);
DISPLAY 0.872340 (1573 3975);
PAINT GREEN (1573 3975);
DISPLAY INVISIBLE (1573 3975);
FORCEADD TAP..1
(1575 4075);
FORCEPROP 3 LASTPIN (1525 4075) SIG_NAME M_C_CPU1_SA_DQS_DP<8>
J 0
(1535 4085);
DISPLAY 0.659574 (1535 4085);
PAINT MONO (1535 4085);
DISPLAY INVISIBLE (1535 4085);
FORCEPROP 1 LASTPIN (1525 4075) BN 8
J 0
(1513 4083);
DISPLAY 0.680851 (1513 4083);
PAINT GREEN (1513 4083);
FORCEPROP 2 LAST CDS_LIB standard
J 0
(1575 4075);
DISPLAY INVISIBLE (1575 4075);
FORCEPROP 1 LAST BODY_TYPE PLUMBING
J 0
(1575 4125);
DISPLAY 0.872340 (1575 4125);
PAINT GREEN (1575 4125);
DISPLAY INVISIBLE (1575 4125);
FORCEPROP 1 LAST HDL_TAP TRUE
J 0
(1900 3950);
DISPLAY 0.872340 (1900 3950);
DISPLAY INVISIBLE (1900 3950);
FORCEPROP 1 LAST PATH I157
J 0
(1573 4075);
DISPLAY 0.872340 (1573 4075);
PAINT GREEN (1573 4075);
DISPLAY INVISIBLE (1573 4075);
FORCEADD TAP..1
(1750 3225);
FORCEPROP 3 LASTPIN (1700 3225) SIG_NAME M_C_CPU1_SA_DQS_DN<0>
J 0
(1710 3235);
DISPLAY 0.659574 (1710 3235);
PAINT MONO (1710 3235);
DISPLAY INVISIBLE (1710 3235);
FORCEPROP 1 LASTPIN (1700 3225) BN 0
J 0
(1688 3233);
DISPLAY 0.680851 (1688 3233);
PAINT GREEN (1688 3233);
FORCEPROP 2 LAST CDS_LIB standard
J 0
(1750 3225);
PAINT MONO (1750 3225);
DISPLAY INVISIBLE (1750 3225);
FORCEPROP 1 LAST BODY_TYPE PLUMBING
J 0
(1750 3275);
DISPLAY 0.872340 (1750 3275);
PAINT GREEN (1750 3275);
DISPLAY INVISIBLE (1750 3275);
FORCEPROP 1 LAST HDL_TAP TRUE
J 0
(2075 3100);
DISPLAY 0.872340 (2075 3100);
DISPLAY INVISIBLE (2075 3100);
FORCEPROP 1 LAST PATH I158
J 0
(1748 3225);
DISPLAY 0.872340 (1748 3225);
PAINT GREEN (1748 3225);
DISPLAY INVISIBLE (1748 3225);
FORCEADD TAP..1
(1750 3325);
FORCEPROP 3 LASTPIN (1700 3325) SIG_NAME M_C_CPU1_SA_DQS_DN<1>
J 0
(1710 3335);
DISPLAY 0.659574 (1710 3335);
PAINT MONO (1710 3335);
DISPLAY INVISIBLE (1710 3335);
FORCEPROP 1 LASTPIN (1700 3325) BN 1
J 0
(1688 3333);
DISPLAY 0.680851 (1688 3333);
PAINT GREEN (1688 3333);
FORCEPROP 2 LAST CDS_LIB standard
J 0
(1750 3325);
DISPLAY INVISIBLE (1750 3325);
FORCEPROP 1 LAST BODY_TYPE PLUMBING
J 0
(1750 3375);
DISPLAY 0.872340 (1750 3375);
PAINT GREEN (1750 3375);
DISPLAY INVISIBLE (1750 3375);
FORCEPROP 1 LAST HDL_TAP TRUE
J 0
(2075 3200);
DISPLAY 0.872340 (2075 3200);
DISPLAY INVISIBLE (2075 3200);
FORCEPROP 1 LAST PATH I159
J 0
(1748 3325);
DISPLAY 0.872340 (1748 3325);
PAINT GREEN (1748 3325);
DISPLAY INVISIBLE (1748 3325);
FORCEADD OFFPAGE..3
R 2
(-3750 2350);
FORCEPROP 2 LAST $XR1 103 
J 0
(-4119 2350);
DISPLAY 0.638298 (-4119 2350);
PAINT MONO (-4119 2350);
FORCEPROP 2 LAST $XR0 53 
J 0
(-3999 2350);
DISPLAY 0.638298 (-3999 2350);
PAINT MONO (-3999 2350);
FORCEPROP 2 LAST CDS_LIB standard
J 0
(-3750 2350);
PAINT MONO (-3750 2350);
DISPLAY INVISIBLE (-3750 2350);
FORCEPROP 1 LAST OFFPAGE TRUE
J 2
(-4075 2225);
DISPLAY 0.872340 (-4075 2225);
DISPLAY INVISIBLE (-4075 2225);
FORCEPROP 1 LAST COMMENT_BODY TRUE
J 2
(-3700 2250);
DISPLAY 0.872340 (-3700 2250);
PAINT GREEN (-3700 2250);
DISPLAY INVISIBLE (-3700 2250);
FORCEPROP 2 LAST PATH I16
J 0
(-3700 2425);
DISPLAY 1.021277 (-3700 2425);
DISPLAY INVISIBLE (-3700 2425);
FORCEADD TAP..1
(1750 3425);
FORCEPROP 3 LASTPIN (1700 3425) SIG_NAME M_C_CPU1_SA_DQS_DN<2>
J 0
(1710 3435);
DISPLAY 0.659574 (1710 3435);
PAINT MONO (1710 3435);
DISPLAY INVISIBLE (1710 3435);
FORCEPROP 1 LASTPIN (1700 3425) BN 2
J 0
(1688 3433);
DISPLAY 0.680851 (1688 3433);
PAINT GREEN (1688 3433);
FORCEPROP 2 LAST CDS_LIB standard
J 0
(1750 3425);
DISPLAY INVISIBLE (1750 3425);
FORCEPROP 1 LAST BODY_TYPE PLUMBING
J 0
(1750 3475);
DISPLAY 0.872340 (1750 3475);
PAINT GREEN (1750 3475);
DISPLAY INVISIBLE (1750 3475);
FORCEPROP 1 LAST HDL_TAP TRUE
J 0
(2075 3300);
DISPLAY 0.872340 (2075 3300);
DISPLAY INVISIBLE (2075 3300);
FORCEPROP 1 LAST PATH I160
J 0
(1748 3425);
DISPLAY 0.872340 (1748 3425);
PAINT GREEN (1748 3425);
DISPLAY INVISIBLE (1748 3425);
FORCEADD TAP..1
(1750 3525);
FORCEPROP 3 LASTPIN (1700 3525) SIG_NAME M_C_CPU1_SA_DQS_DN<3>
J 0
(1710 3535);
DISPLAY 0.659574 (1710 3535);
PAINT MONO (1710 3535);
DISPLAY INVISIBLE (1710 3535);
FORCEPROP 1 LASTPIN (1700 3525) BN 3
J 0
(1688 3533);
DISPLAY 0.680851 (1688 3533);
PAINT GREEN (1688 3533);
FORCEPROP 2 LAST CDS_LIB standard
J 0
(1750 3525);
PAINT MONO (1750 3525);
DISPLAY INVISIBLE (1750 3525);
FORCEPROP 1 LAST BODY_TYPE PLUMBING
J 0
(1750 3575);
DISPLAY 0.872340 (1750 3575);
PAINT GREEN (1750 3575);
DISPLAY INVISIBLE (1750 3575);
FORCEPROP 1 LAST HDL_TAP TRUE
J 0
(2075 3400);
DISPLAY 0.872340 (2075 3400);
DISPLAY INVISIBLE (2075 3400);
FORCEPROP 1 LAST PATH I161
J 0
(1748 3525);
DISPLAY 0.872340 (1748 3525);
PAINT GREEN (1748 3525);
DISPLAY INVISIBLE (1748 3525);
FORCEADD TAP..1
(1750 3725);
FORCEPROP 3 LASTPIN (1700 3725) SIG_NAME M_C_CPU1_SA_DQS_DN<5>
J 0
(1710 3735);
DISPLAY 0.659574 (1710 3735);
PAINT MONO (1710 3735);
DISPLAY INVISIBLE (1710 3735);
FORCEPROP 1 LASTPIN (1700 3725) BN 5
J 0
(1688 3733);
DISPLAY 0.680851 (1688 3733);
PAINT GREEN (1688 3733);
FORCEPROP 2 LAST CDS_LIB standard
J 0
(1750 3725);
DISPLAY INVISIBLE (1750 3725);
FORCEPROP 1 LAST BODY_TYPE PLUMBING
J 0
(1750 3775);
DISPLAY 0.872340 (1750 3775);
PAINT GREEN (1750 3775);
DISPLAY INVISIBLE (1750 3775);
FORCEPROP 1 LAST HDL_TAP TRUE
J 0
(2075 3600);
DISPLAY 0.872340 (2075 3600);
DISPLAY INVISIBLE (2075 3600);
FORCEPROP 1 LAST PATH I162
J 0
(1748 3725);
DISPLAY 0.872340 (1748 3725);
PAINT GREEN (1748 3725);
DISPLAY INVISIBLE (1748 3725);
FORCEADD TAP..1
(1750 3625);
FORCEPROP 3 LASTPIN (1700 3625) SIG_NAME M_C_CPU1_SA_DQS_DN<4>
J 0
(1710 3635);
DISPLAY 0.659574 (1710 3635);
PAINT MONO (1710 3635);
DISPLAY INVISIBLE (1710 3635);
FORCEPROP 1 LASTPIN (1700 3625) BN 4
J 0
(1688 3633);
DISPLAY 0.680851 (1688 3633);
PAINT GREEN (1688 3633);
FORCEPROP 2 LAST CDS_LIB standard
J 0
(1750 3625);
PAINT MONO (1750 3625);
DISPLAY INVISIBLE (1750 3625);
FORCEPROP 1 LAST BODY_TYPE PLUMBING
J 0
(1750 3675);
DISPLAY 0.872340 (1750 3675);
PAINT GREEN (1750 3675);
DISPLAY INVISIBLE (1750 3675);
FORCEPROP 1 LAST HDL_TAP TRUE
J 0
(2075 3500);
DISPLAY 0.872340 (2075 3500);
DISPLAY INVISIBLE (2075 3500);
FORCEPROP 1 LAST PATH I163
J 0
(1748 3625);
DISPLAY 0.872340 (1748 3625);
PAINT GREEN (1748 3625);
DISPLAY INVISIBLE (1748 3625);
FORCEADD TAP..1
(1750 3825);
FORCEPROP 3 LASTPIN (1700 3825) SIG_NAME M_C_CPU1_SA_DQS_DN<6>
J 0
(1710 3835);
DISPLAY 0.659574 (1710 3835);
PAINT MONO (1710 3835);
DISPLAY INVISIBLE (1710 3835);
FORCEPROP 1 LASTPIN (1700 3825) BN 6
J 0
(1688 3833);
DISPLAY 0.680851 (1688 3833);
PAINT GREEN (1688 3833);
FORCEPROP 2 LAST CDS_LIB standard
J 0
(1750 3825);
DISPLAY INVISIBLE (1750 3825);
FORCEPROP 1 LAST BODY_TYPE PLUMBING
J 0
(1750 3875);
DISPLAY 0.872340 (1750 3875);
PAINT GREEN (1750 3875);
DISPLAY INVISIBLE (1750 3875);
FORCEPROP 1 LAST HDL_TAP TRUE
J 0
(2075 3700);
DISPLAY 0.872340 (2075 3700);
DISPLAY INVISIBLE (2075 3700);
FORCEPROP 1 LAST PATH I164
J 0
(1748 3825);
DISPLAY 0.872340 (1748 3825);
PAINT GREEN (1748 3825);
DISPLAY INVISIBLE (1748 3825);
FORCEADD TAP..1
(1750 3925);
FORCEPROP 3 LASTPIN (1700 3925) SIG_NAME M_C_CPU1_SA_DQS_DN<7>
J 0
(1710 3935);
DISPLAY 0.659574 (1710 3935);
PAINT MONO (1710 3935);
DISPLAY INVISIBLE (1710 3935);
FORCEPROP 1 LASTPIN (1700 3925) BN 7
J 0
(1688 3933);
DISPLAY 0.680851 (1688 3933);
PAINT GREEN (1688 3933);
FORCEPROP 2 LAST CDS_LIB standard
J 0
(1750 3925);
DISPLAY INVISIBLE (1750 3925);
FORCEPROP 1 LAST BODY_TYPE PLUMBING
J 0
(1750 3975);
DISPLAY 0.872340 (1750 3975);
PAINT GREEN (1750 3975);
DISPLAY INVISIBLE (1750 3975);
FORCEPROP 1 LAST HDL_TAP TRUE
J 0
(2075 3800);
DISPLAY 0.872340 (2075 3800);
DISPLAY INVISIBLE (2075 3800);
FORCEPROP 1 LAST PATH I165
J 0
(1748 3925);
DISPLAY 0.872340 (1748 3925);
PAINT GREEN (1748 3925);
DISPLAY INVISIBLE (1748 3925);
FORCEADD TAP..1
(1750 4025);
FORCEPROP 3 LASTPIN (1700 4025) SIG_NAME M_C_CPU1_SA_DQS_DN<8>
J 0
(1710 4035);
DISPLAY 0.659574 (1710 4035);
PAINT MONO (1710 4035);
DISPLAY INVISIBLE (1710 4035);
FORCEPROP 1 LASTPIN (1700 4025) BN 8
J 0
(1688 4033);
DISPLAY 0.680851 (1688 4033);
PAINT GREEN (1688 4033);
FORCEPROP 2 LAST CDS_LIB standard
J 0
(1750 4025);
DISPLAY INVISIBLE (1750 4025);
FORCEPROP 1 LAST BODY_TYPE PLUMBING
J 0
(1750 4075);
DISPLAY 0.872340 (1750 4075);
PAINT GREEN (1750 4075);
DISPLAY INVISIBLE (1750 4075);
FORCEPROP 1 LAST HDL_TAP TRUE
J 0
(2075 3900);
DISPLAY 0.872340 (2075 3900);
DISPLAY INVISIBLE (2075 3900);
FORCEPROP 1 LAST PATH I166
J 0
(1748 4025);
DISPLAY 0.872340 (1748 4025);
PAINT GREEN (1748 4025);
DISPLAY INVISIBLE (1748 4025);
FORCEADD Q_CAP..1
(2175 300);
FORCEPROP 1 LAST PART_NUMBER CH6103KEA00
J 0
(2225 150);
DISPLAY 0.978723 (2225 150);
DISPLAY INVISIBLE (2225 150);
FORCEPROP 1 LAST VALUE 10UF
J 0
(2225 350);
DISPLAY 0.978723 (2225 350);
FORCEPROP 1 LAST PACK_TYPE C0805
J 0
(2225 100);
DISPLAY 0.978723 (2225 100);
FORCEPROP 1 LAST VOLTAGE 16V
J 0
(2225 300);
DISPLAY 0.978723 (2225 300);
FORCEPROP 1 LAST TOLERANCE 10%
J 0
(2225 250);
DISPLAY 0.978723 (2225 250);
FORCEPROP 1 LAST MATERIAL X6S
J 0
(2225 200);
DISPLAY 0.978723 (2225 200);
FORCEPROP 1 LAST $LOCATION C64
J 0
(2225 400);
DISPLAY 0.978723 (2225 400);
FORCEPROP 1 LASTPIN (2175 400) $PN 1
J 0
(2185 380);
DISPLAY 0.787234 (2185 380);
FORCEPROP 1 LASTPIN (2175 200) $PN 2
J 0
(2185 180);
DISPLAY 0.787234 (2185 180);
FORCEPROP 2 LAST CDS_LIB pure_quanta
J 0
(2175 300);
PAINT MONO (2175 300);
DISPLAY INVISIBLE (2175 300);
FORCEPROP 1 LAST PATH I167
J 0
(2225 450);
DISPLAY 0.978723 (2225 450);
PAINT WHITE (2225 450);
DISPLAY INVISIBLE (2225 450);
FORCEPROP 1 LAST $LOCATION C64
J 0
(2225 500);
DISPLAY 1.021277 (2225 500);
DISPLAY INVISIBLE (2225 500);
FORCEPROP 2 LAST CDS_LOCATION C64
J 0
(2225 500);
DISPLAY 1.021277 (2225 500);
DISPLAY INVISIBLE (2225 500);
FORCEPROP 2 LAST $SEC 1
J 0
(2225 500);
DISPLAY 0.680851 (2225 500);
PAINT MONO (2225 500);
DISPLAY INVISIBLE (2225 500);
FORCEPROP 2 LAST CDS_SEC 1
J 0
(2225 500);
DISPLAY 1.021277 (2225 500);
DISPLAY INVISIBLE (2225 500);
FORCEADD UNIVERSAL_GND..1
(3250 475);
FORCEPROP 3 LASTPIN (3250 525) SIG_NAME GND\g
J 0
(3260 535);
DISPLAY 0.659574 (3260 535);
PAINT MONO (3260 535);
DISPLAY INVISIBLE (3260 535);
FORCEPROP 1 LAST PATH I168
J 0
(3325 475);
DISPLAY 0.872340 (3325 475);
PAINT AQUA (3325 475);
DISPLAY INVISIBLE (3325 475);
FORCEPROP 1 LAST HDL_POWER GND
J 1
(3275 400);
DISPLAY 0.872340 (3275 400);
PAINT GREEN (3275 400);
DISPLAY INVISIBLE (3275 400);
FORCEPROP 2 LAST CDS_LIB logical_power
J 0
(3250 475);
PAINT MONO (3250 475);
DISPLAY INVISIBLE (3250 475);
FORCEADD SCONN288_ADR50017P130CC..3
(4100 2550);
FORCEPROP 1 LAST PART_NUMBER DFHST8FS461
J 0
(3645 4474);
DISPLAY 0.723404 (3645 4474);
PAINT GREEN (3645 4474);
DISPLAY INVISIBLE (3645 4474);
FORCEPROP 1 LAST MATERIAL IO
J 0
(3645 4347);
DISPLAY 0.723404 (3645 4347);
PAINT GREEN (3645 4347);
FORCEPROP 2 LAST PART_TYPE SMLF
J 0
(3650 4625);
DISPLAY 1.021277 (3650 4625);
FORCEPROP 2 LAST VALUE SCONN288_ADR50017-P130CC
J 0
(3650 4575);
DISPLAY 1.021277 (3650 4575);
FORCEPROP 1 LAST $LOCATION J21
J 0
(3650 4525);
DISPLAY 0.723404 (3650 4525);
PAINT GREEN (3650 4525);
FORCEPROP 0 LASTPIN (4700 925) $PN G1
J 0
(4710 935);
DISPLAY 0.680851 (4710 935);
PAINT MONO (4710 935);
FORCEPROP 0 LASTPIN (4700 875) $PN G2
J 0
(4710 885);
DISPLAY 0.680851 (4710 885);
PAINT MONO (4710 885);
FORCEPROP 0 LASTPIN (4700 825) $PN G3
J 0
(4710 835);
DISPLAY 0.680851 (4710 835);
PAINT MONO (4710 835);
FORCEPROP 0 LASTPIN (3500 4075) $PN 1
J 2
(3490 4085);
DISPLAY 0.680851 (3490 4085);
PAINT MONO (3490 4085);
FORCEPROP 0 LASTPIN (3500 4125) $PN 145
J 2
(3490 4135);
DISPLAY 0.680851 (3490 4135);
PAINT MONO (3490 4135);
FORCEPROP 0 LASTPIN (3500 4175) $PN 146
J 2
(3490 4185);
DISPLAY 0.680851 (3490 4185);
PAINT MONO (3490 4185);
FORCEPROP 0 LASTPIN (4700 1025) $PN 6
J 0
(4710 1035);
DISPLAY 0.680851 (4710 1035);
PAINT MONO (4710 1035);
FORCEPROP 0 LASTPIN (4700 1075) $PN 8
J 0
(4710 1085);
DISPLAY 0.680851 (4710 1085);
PAINT MONO (4710 1085);
FORCEPROP 0 LASTPIN (4700 1125) $PN 10
J 0
(4710 1135);
DISPLAY 0.680851 (4710 1135);
PAINT MONO (4710 1135);
FORCEPROP 0 LASTPIN (4700 1175) $PN 13
J 0
(4710 1185);
DISPLAY 0.680851 (4710 1185);
PAINT MONO (4710 1185);
FORCEPROP 0 LASTPIN (4700 1225) $PN 15
J 0
(4710 1235);
DISPLAY 0.680851 (4710 1235);
PAINT MONO (4710 1235);
FORCEPROP 0 LASTPIN (4700 1275) $PN 17
J 0
(4710 1285);
DISPLAY 0.680851 (4710 1285);
PAINT MONO (4710 1285);
FORCEPROP 0 LASTPIN (4700 1325) $PN 19
J 0
(4710 1335);
DISPLAY 0.680851 (4710 1335);
PAINT MONO (4710 1335);
FORCEPROP 0 LASTPIN (4700 1375) $PN 21
J 0
(4710 1385);
DISPLAY 0.680851 (4710 1385);
PAINT MONO (4710 1385);
FORCEPROP 0 LASTPIN (4700 1425) $PN 24
J 0
(4710 1435);
DISPLAY 0.680851 (4710 1435);
PAINT MONO (4710 1435);
FORCEPROP 0 LASTPIN (4700 1475) $PN 26
J 0
(4710 1485);
DISPLAY 0.680851 (4710 1485);
PAINT MONO (4710 1485);
FORCEPROP 0 LASTPIN (4700 1525) $PN 28
J 0
(4710 1535);
DISPLAY 0.680851 (4710 1535);
PAINT MONO (4710 1535);
FORCEPROP 0 LASTPIN (4700 1575) $PN 30
J 0
(4710 1585);
DISPLAY 0.680851 (4710 1585);
PAINT MONO (4710 1585);
FORCEPROP 0 LASTPIN (4700 1625) $PN 32
J 0
(4710 1635);
DISPLAY 0.680851 (4710 1635);
PAINT MONO (4710 1635);
FORCEPROP 0 LASTPIN (4700 1675) $PN 35
J 0
(4710 1685);
DISPLAY 0.680851 (4710 1685);
PAINT MONO (4710 1685);
FORCEPROP 0 LASTPIN (4700 1725) $PN 37
J 0
(4710 1735);
DISPLAY 0.680851 (4710 1735);
PAINT MONO (4710 1735);
FORCEPROP 0 LASTPIN (4700 1775) $PN 39
J 0
(4710 1785);
DISPLAY 0.680851 (4710 1785);
PAINT MONO (4710 1785);
FORCEPROP 0 LASTPIN (4700 1825) $PN 41
J 0
(4710 1835);
DISPLAY 0.680851 (4710 1835);
PAINT MONO (4710 1835);
FORCEPROP 0 LASTPIN (4700 1875) $PN 43
J 0
(4710 1885);
DISPLAY 0.680851 (4710 1885);
PAINT MONO (4710 1885);
FORCEPROP 0 LASTPIN (4700 1925) $PN 46
J 0
(4710 1935);
DISPLAY 0.680851 (4710 1935);
PAINT MONO (4710 1935);
FORCEPROP 0 LASTPIN (4700 1975) $PN 48
J 0
(4710 1985);
DISPLAY 0.680851 (4710 1985);
PAINT MONO (4710 1985);
FORCEPROP 0 LASTPIN (4700 2025) $PN 50
J 0
(4710 2035);
DISPLAY 0.680851 (4710 2035);
PAINT MONO (4710 2035);
FORCEPROP 0 LASTPIN (4700 2075) $PN 52
J 0
(4710 2085);
DISPLAY 0.680851 (4710 2085);
PAINT MONO (4710 2085);
FORCEPROP 0 LASTPIN (4700 2125) $PN 54
J 0
(4710 2135);
DISPLAY 0.680851 (4710 2135);
PAINT MONO (4710 2135);
FORCEPROP 0 LASTPIN (4700 2175) $PN 57
J 0
(4710 2185);
DISPLAY 0.680851 (4710 2185);
PAINT MONO (4710 2185);
FORCEPROP 0 LASTPIN (4700 2225) $PN 59
J 0
(4710 2235);
DISPLAY 0.680851 (4710 2235);
PAINT MONO (4710 2235);
FORCEPROP 0 LASTPIN (4700 2275) $PN 61
J 0
(4710 2285);
DISPLAY 0.680851 (4710 2285);
PAINT MONO (4710 2285);
FORCEPROP 0 LASTPIN (4700 2325) $PN 63
J 0
(4710 2335);
DISPLAY 0.680851 (4710 2335);
PAINT MONO (4710 2335);
FORCEPROP 0 LASTPIN (4700 2375) $PN 65
J 0
(4710 2385);
DISPLAY 0.680851 (4710 2385);
PAINT MONO (4710 2385);
FORCEPROP 0 LASTPIN (4700 2425) $PN 67
J 0
(4710 2435);
DISPLAY 0.680851 (4710 2435);
PAINT MONO (4710 2435);
FORCEPROP 0 LASTPIN (4700 2475) $PN 69
J 0
(4710 2485);
DISPLAY 0.680851 (4710 2485);
PAINT MONO (4710 2485);
FORCEPROP 0 LASTPIN (4700 2525) $PN 71
J 0
(4710 2535);
DISPLAY 0.680851 (4710 2535);
PAINT MONO (4710 2535);
FORCEPROP 0 LASTPIN (4700 2575) $PN 73
J 0
(4710 2585);
DISPLAY 0.680851 (4710 2585);
PAINT MONO (4710 2585);
FORCEPROP 0 LASTPIN (4700 2625) $PN 75
J 0
(4710 2635);
DISPLAY 0.680851 (4710 2635);
PAINT MONO (4710 2635);
FORCEPROP 0 LASTPIN (4700 2675) $PN 77
J 0
(4710 2685);
DISPLAY 0.680851 (4710 2685);
PAINT MONO (4710 2685);
FORCEPROP 0 LASTPIN (4700 2725) $PN 79
J 0
(4710 2735);
DISPLAY 0.680851 (4710 2735);
PAINT MONO (4710 2735);
FORCEPROP 0 LASTPIN (4700 2775) $PN 81
J 0
(4710 2785);
DISPLAY 0.680851 (4710 2785);
PAINT MONO (4710 2785);
FORCEPROP 0 LASTPIN (4700 2825) $PN 83
J 0
(4710 2835);
DISPLAY 0.680851 (4710 2835);
PAINT MONO (4710 2835);
FORCEPROP 0 LASTPIN (4700 2875) $PN 85
J 0
(4710 2885);
DISPLAY 0.680851 (4710 2885);
PAINT MONO (4710 2885);
FORCEPROP 0 LASTPIN (4700 2925) $PN 88
J 0
(4710 2935);
DISPLAY 0.680851 (4710 2935);
PAINT MONO (4710 2935);
FORCEPROP 0 LASTPIN (4700 2975) $PN 90
J 0
(4710 2985);
DISPLAY 0.680851 (4710 2985);
PAINT MONO (4710 2985);
FORCEPROP 0 LASTPIN (4700 3025) $PN 92
J 0
(4710 3035);
DISPLAY 0.680851 (4710 3035);
PAINT MONO (4710 3035);
FORCEPROP 0 LASTPIN (4700 3075) $PN 95
J 0
(4710 3085);
DISPLAY 0.680851 (4710 3085);
PAINT MONO (4710 3085);
FORCEPROP 0 LASTPIN (4700 3125) $PN 97
J 0
(4710 3135);
DISPLAY 0.680851 (4710 3135);
PAINT MONO (4710 3135);
FORCEPROP 0 LASTPIN (4700 3175) $PN 99
J 0
(4710 3185);
DISPLAY 0.680851 (4710 3185);
PAINT MONO (4710 3185);
FORCEPROP 0 LASTPIN (4700 3225) $PN 101
J 0
(4710 3235);
DISPLAY 0.680851 (4710 3235);
PAINT MONO (4710 3235);
FORCEPROP 0 LASTPIN (4700 3275) $PN 103
J 0
(4710 3285);
DISPLAY 0.680851 (4710 3285);
PAINT MONO (4710 3285);
FORCEPROP 0 LASTPIN (4700 3325) $PN 106
J 0
(4710 3335);
DISPLAY 0.680851 (4710 3335);
PAINT MONO (4710 3335);
FORCEPROP 0 LASTPIN (4700 3375) $PN 108
J 0
(4710 3385);
DISPLAY 0.680851 (4710 3385);
PAINT MONO (4710 3385);
FORCEPROP 0 LASTPIN (4700 3425) $PN 110
J 0
(4710 3435);
DISPLAY 0.680851 (4710 3435);
PAINT MONO (4710 3435);
FORCEPROP 0 LASTPIN (4700 3475) $PN 112
J 0
(4710 3485);
DISPLAY 0.680851 (4710 3485);
PAINT MONO (4710 3485);
FORCEPROP 0 LASTPIN (4700 3525) $PN 114
J 0
(4710 3535);
DISPLAY 0.680851 (4710 3535);
PAINT MONO (4710 3535);
FORCEPROP 0 LASTPIN (4700 3575) $PN 117
J 0
(4710 3585);
DISPLAY 0.680851 (4710 3585);
PAINT MONO (4710 3585);
FORCEPROP 0 LASTPIN (4700 3625) $PN 119
J 0
(4710 3635);
DISPLAY 0.680851 (4710 3635);
PAINT MONO (4710 3635);
FORCEPROP 0 LASTPIN (4700 3675) $PN 121
J 0
(4710 3685);
DISPLAY 0.680851 (4710 3685);
PAINT MONO (4710 3685);
FORCEPROP 0 LASTPIN (4700 3725) $PN 123
J 0
(4710 3735);
DISPLAY 0.680851 (4710 3735);
PAINT MONO (4710 3735);
FORCEPROP 0 LASTPIN (4700 3775) $PN 125
J 0
(4710 3785);
DISPLAY 0.680851 (4710 3785);
PAINT MONO (4710 3785);
FORCEPROP 0 LASTPIN (4700 3825) $PN 128
J 0
(4710 3835);
DISPLAY 0.680851 (4710 3835);
PAINT MONO (4710 3835);
FORCEPROP 0 LASTPIN (4700 3875) $PN 130
J 0
(4710 3885);
DISPLAY 0.680851 (4710 3885);
PAINT MONO (4710 3885);
FORCEPROP 0 LASTPIN (4700 3925) $PN 132
J 0
(4710 3935);
DISPLAY 0.680851 (4710 3935);
PAINT MONO (4710 3935);
FORCEPROP 0 LASTPIN (4700 3975) $PN 134
J 0
(4710 3985);
DISPLAY 0.680851 (4710 3985);
PAINT MONO (4710 3985);
FORCEPROP 0 LASTPIN (4700 4025) $PN 136
J 0
(4710 4035);
DISPLAY 0.680851 (4710 4035);
PAINT MONO (4710 4035);
FORCEPROP 0 LASTPIN (4700 4075) $PN 139
J 0
(4710 4085);
DISPLAY 0.680851 (4710 4085);
PAINT MONO (4710 4085);
FORCEPROP 0 LASTPIN (4700 4125) $PN 141
J 0
(4710 4135);
DISPLAY 0.680851 (4710 4135);
PAINT MONO (4710 4135);
FORCEPROP 0 LASTPIN (4700 4175) $PN 143
J 0
(4710 4185);
DISPLAY 0.680851 (4710 4185);
PAINT MONO (4710 4185);
FORCEPROP 0 LASTPIN (3500 925) $PN 151
J 2
(3490 935);
DISPLAY 0.680851 (3490 935);
PAINT MONO (3490 935);
FORCEPROP 0 LASTPIN (3500 975) $PN 153
J 2
(3490 985);
DISPLAY 0.680851 (3490 985);
PAINT MONO (3490 985);
FORCEPROP 0 LASTPIN (3500 1025) $PN 155
J 2
(3490 1035);
DISPLAY 0.680851 (3490 1035);
PAINT MONO (3490 1035);
FORCEPROP 0 LASTPIN (3500 1075) $PN 158
J 2
(3490 1085);
DISPLAY 0.680851 (3490 1085);
PAINT MONO (3490 1085);
FORCEPROP 0 LASTPIN (3500 1125) $PN 160
J 2
(3490 1135);
DISPLAY 0.680851 (3490 1135);
PAINT MONO (3490 1135);
FORCEPROP 0 LASTPIN (3500 1175) $PN 162
J 2
(3490 1185);
DISPLAY 0.680851 (3490 1185);
PAINT MONO (3490 1185);
FORCEPROP 0 LASTPIN (3500 1225) $PN 164
J 2
(3490 1235);
DISPLAY 0.680851 (3490 1235);
PAINT MONO (3490 1235);
FORCEPROP 0 LASTPIN (3500 1275) $PN 166
J 2
(3490 1285);
DISPLAY 0.680851 (3490 1285);
PAINT MONO (3490 1285);
FORCEPROP 0 LASTPIN (3500 1325) $PN 169
J 2
(3490 1335);
DISPLAY 0.680851 (3490 1335);
PAINT MONO (3490 1335);
FORCEPROP 0 LASTPIN (3500 1375) $PN 171
J 2
(3490 1385);
DISPLAY 0.680851 (3490 1385);
PAINT MONO (3490 1385);
FORCEPROP 0 LASTPIN (3500 1425) $PN 173
J 2
(3490 1435);
DISPLAY 0.680851 (3490 1435);
PAINT MONO (3490 1435);
FORCEPROP 0 LASTPIN (3500 1475) $PN 175
J 2
(3490 1485);
DISPLAY 0.680851 (3490 1485);
PAINT MONO (3490 1485);
FORCEPROP 0 LASTPIN (3500 1525) $PN 177
J 2
(3490 1535);
DISPLAY 0.680851 (3490 1535);
PAINT MONO (3490 1535);
FORCEPROP 0 LASTPIN (3500 1575) $PN 180
J 2
(3490 1585);
DISPLAY 0.680851 (3490 1585);
PAINT MONO (3490 1585);
FORCEPROP 0 LASTPIN (3500 1625) $PN 182
J 2
(3490 1635);
DISPLAY 0.680851 (3490 1635);
PAINT MONO (3490 1635);
FORCEPROP 0 LASTPIN (3500 1675) $PN 184
J 2
(3490 1685);
DISPLAY 0.680851 (3490 1685);
PAINT MONO (3490 1685);
FORCEPROP 0 LASTPIN (3500 1725) $PN 186
J 2
(3490 1735);
DISPLAY 0.680851 (3490 1735);
PAINT MONO (3490 1735);
FORCEPROP 0 LASTPIN (3500 1775) $PN 188
J 2
(3490 1785);
DISPLAY 0.680851 (3490 1785);
PAINT MONO (3490 1785);
FORCEPROP 0 LASTPIN (3500 1825) $PN 191
J 2
(3490 1835);
DISPLAY 0.680851 (3490 1835);
PAINT MONO (3490 1835);
FORCEPROP 0 LASTPIN (3500 1875) $PN 193
J 2
(3490 1885);
DISPLAY 0.680851 (3490 1885);
PAINT MONO (3490 1885);
FORCEPROP 0 LASTPIN (3500 1925) $PN 195
J 2
(3490 1935);
DISPLAY 0.680851 (3490 1935);
PAINT MONO (3490 1935);
FORCEPROP 0 LASTPIN (3500 1975) $PN 197
J 2
(3490 1985);
DISPLAY 0.680851 (3490 1985);
PAINT MONO (3490 1985);
FORCEPROP 0 LASTPIN (3500 2025) $PN 199
J 2
(3490 2035);
DISPLAY 0.680851 (3490 2035);
PAINT MONO (3490 2035);
FORCEPROP 0 LASTPIN (3500 2075) $PN 202
J 2
(3490 2085);
DISPLAY 0.680851 (3490 2085);
PAINT MONO (3490 2085);
FORCEPROP 0 LASTPIN (3500 2125) $PN 204
J 2
(3490 2135);
DISPLAY 0.680851 (3490 2135);
PAINT MONO (3490 2135);
FORCEPROP 0 LASTPIN (3500 2175) $PN 206
J 2
(3490 2185);
DISPLAY 0.680851 (3490 2185);
PAINT MONO (3490 2185);
FORCEPROP 0 LASTPIN (3500 2225) $PN 208
J 2
(3490 2235);
DISPLAY 0.680851 (3490 2235);
PAINT MONO (3490 2235);
FORCEPROP 0 LASTPIN (3500 2275) $PN 210
J 2
(3490 2285);
DISPLAY 0.680851 (3490 2285);
PAINT MONO (3490 2285);
FORCEPROP 0 LASTPIN (3500 2325) $PN 212
J 2
(3490 2335);
DISPLAY 0.680851 (3490 2335);
PAINT MONO (3490 2335);
FORCEPROP 0 LASTPIN (3500 2375) $PN 214
J 2
(3490 2385);
DISPLAY 0.680851 (3490 2385);
PAINT MONO (3490 2385);
FORCEPROP 0 LASTPIN (3500 2425) $PN 216
J 2
(3490 2435);
DISPLAY 0.680851 (3490 2435);
PAINT MONO (3490 2435);
FORCEPROP 0 LASTPIN (3500 2475) $PN 219
J 2
(3490 2485);
DISPLAY 0.680851 (3490 2485);
PAINT MONO (3490 2485);
FORCEPROP 0 LASTPIN (3500 2525) $PN 222
J 2
(3490 2535);
DISPLAY 0.680851 (3490 2535);
PAINT MONO (3490 2535);
FORCEPROP 0 LASTPIN (3500 2575) $PN 224
J 2
(3490 2585);
DISPLAY 0.680851 (3490 2585);
PAINT MONO (3490 2585);
FORCEPROP 0 LASTPIN (3500 2625) $PN 226
J 2
(3490 2635);
DISPLAY 0.680851 (3490 2635);
PAINT MONO (3490 2635);
FORCEPROP 0 LASTPIN (3500 2675) $PN 228
J 2
(3490 2685);
DISPLAY 0.680851 (3490 2685);
PAINT MONO (3490 2685);
FORCEPROP 0 LASTPIN (3500 2725) $PN 230
J 2
(3490 2735);
DISPLAY 0.680851 (3490 2735);
PAINT MONO (3490 2735);
FORCEPROP 0 LASTPIN (3500 2775) $PN 233
J 2
(3490 2785);
DISPLAY 0.680851 (3490 2785);
PAINT MONO (3490 2785);
FORCEPROP 0 LASTPIN (3500 2825) $PN 235
J 2
(3490 2835);
DISPLAY 0.680851 (3490 2835);
PAINT MONO (3490 2835);
FORCEPROP 0 LASTPIN (3500 2875) $PN 237
J 2
(3490 2885);
DISPLAY 0.680851 (3490 2885);
PAINT MONO (3490 2885);
FORCEPROP 0 LASTPIN (3500 2925) $PN 240
J 2
(3490 2935);
DISPLAY 0.680851 (3490 2935);
PAINT MONO (3490 2935);
FORCEPROP 0 LASTPIN (3500 2975) $PN 242
J 2
(3490 2985);
DISPLAY 0.680851 (3490 2985);
PAINT MONO (3490 2985);
FORCEPROP 0 LASTPIN (3500 3025) $PN 244
J 2
(3490 3035);
DISPLAY 0.680851 (3490 3035);
PAINT MONO (3490 3035);
FORCEPROP 0 LASTPIN (3500 3075) $PN 246
J 2
(3490 3085);
DISPLAY 0.680851 (3490 3085);
PAINT MONO (3490 3085);
FORCEPROP 0 LASTPIN (3500 3125) $PN 248
J 2
(3490 3135);
DISPLAY 0.680851 (3490 3135);
PAINT MONO (3490 3135);
FORCEPROP 0 LASTPIN (3500 3175) $PN 251
J 2
(3490 3185);
DISPLAY 0.680851 (3490 3185);
PAINT MONO (3490 3185);
FORCEPROP 0 LASTPIN (3500 3225) $PN 253
J 2
(3490 3235);
DISPLAY 0.680851 (3490 3235);
PAINT MONO (3490 3235);
FORCEPROP 0 LASTPIN (3500 3275) $PN 255
J 2
(3490 3285);
DISPLAY 0.680851 (3490 3285);
PAINT MONO (3490 3285);
FORCEPROP 0 LASTPIN (3500 3325) $PN 257
J 2
(3490 3335);
DISPLAY 0.680851 (3490 3335);
PAINT MONO (3490 3335);
FORCEPROP 0 LASTPIN (3500 3375) $PN 259
J 2
(3490 3385);
DISPLAY 0.680851 (3490 3385);
PAINT MONO (3490 3385);
FORCEPROP 0 LASTPIN (3500 3425) $PN 262
J 2
(3490 3435);
DISPLAY 0.680851 (3490 3435);
PAINT MONO (3490 3435);
FORCEPROP 0 LASTPIN (3500 3475) $PN 264
J 2
(3490 3485);
DISPLAY 0.680851 (3490 3485);
PAINT MONO (3490 3485);
FORCEPROP 0 LASTPIN (3500 3525) $PN 266
J 2
(3490 3535);
DISPLAY 0.680851 (3490 3535);
PAINT MONO (3490 3535);
FORCEPROP 0 LASTPIN (3500 3575) $PN 268
J 2
(3490 3585);
DISPLAY 0.680851 (3490 3585);
PAINT MONO (3490 3585);
FORCEPROP 0 LASTPIN (3500 3625) $PN 270
J 2
(3490 3635);
DISPLAY 0.680851 (3490 3635);
PAINT MONO (3490 3635);
FORCEPROP 0 LASTPIN (3500 3675) $PN 273
J 2
(3490 3685);
DISPLAY 0.680851 (3490 3685);
PAINT MONO (3490 3685);
FORCEPROP 0 LASTPIN (3500 3725) $PN 275
J 2
(3490 3735);
DISPLAY 0.680851 (3490 3735);
PAINT MONO (3490 3735);
FORCEPROP 0 LASTPIN (3500 3775) $PN 277
J 2
(3490 3785);
DISPLAY 0.680851 (3490 3785);
PAINT MONO (3490 3785);
FORCEPROP 0 LASTPIN (3500 3825) $PN 279
J 2
(3490 3835);
DISPLAY 0.680851 (3490 3835);
PAINT MONO (3490 3835);
FORCEPROP 0 LASTPIN (3500 3875) $PN 281
J 2
(3490 3885);
DISPLAY 0.680851 (3490 3885);
PAINT MONO (3490 3885);
FORCEPROP 0 LASTPIN (3500 3925) $PN 284
J 2
(3490 3935);
DISPLAY 0.680851 (3490 3935);
PAINT MONO (3490 3935);
FORCEPROP 0 LASTPIN (3500 3975) $PN 286
J 2
(3490 3985);
DISPLAY 0.680851 (3490 3985);
PAINT MONO (3490 3985);
FORCEPROP 0 LASTPIN (3500 4025) $PN 288
J 2
(3490 4035);
DISPLAY 0.680851 (3490 4035);
PAINT MONO (3490 4035);
FORCEPROP 1 LAST NEEDS_NO_SIZE TRUE
J 0
(4100 2550);
DISPLAY 0.723404 (4100 2550);
PAINT GREEN (4100 2550);
DISPLAY INVISIBLE (4100 2550);
FORCEPROP 1 LAST CDS_LMAN_SYM_OUTLINE -450,1775,450,-1775
J 0
(4100 2550);
DISPLAY 0.468085 (4100 2550);
PAINT GREEN (4100 2550);
DISPLAY INVISIBLE (4100 2550);
FORCEPROP 2 LAST CDS_LIB pure_quanta
J 0
(4100 2550);
DISPLAY INVISIBLE (4100 2550);
FORCEPROP 1 LAST PATH I169
J 0
(4100 2550);
DISPLAY 0.723404 (4100 2550);
PAINT GREEN (4100 2550);
DISPLAY INVISIBLE (4100 2550);
FORCEPROP 2 LAST CDS_LOCATION J21
J 0
(3650 4675);
DISPLAY 1.021277 (3650 4675);
DISPLAY INVISIBLE (3650 4675);
FORCEPROP 0 LAST $SEC 3
J 0
(3650 4675);
DISPLAY 0.680851 (3650 4675);
PAINT MONO (3650 4675);
DISPLAY INVISIBLE (3650 4675);
FORCEPROP 2 LAST CDS_SEC 3
J 0
(3650 4675);
DISPLAY 1.021277 (3650 4675);
DISPLAY INVISIBLE (3650 4675);
FORCEADD OFFPAGE..3
R 2
(-3750 2800);
FORCEPROP 2 LAST $XR1 103 
J 0
(-4119 2800);
DISPLAY 0.638298 (-4119 2800);
PAINT MONO (-4119 2800);
FORCEPROP 2 LAST $XR0 53 
J 0
(-3999 2800);
DISPLAY 0.638298 (-3999 2800);
PAINT MONO (-3999 2800);
FORCEPROP 2 LAST CDS_LIB standard
J 0
(-3750 2800);
PAINT MONO (-3750 2800);
DISPLAY INVISIBLE (-3750 2800);
FORCEPROP 1 LAST OFFPAGE TRUE
J 2
(-4075 2675);
DISPLAY 0.872340 (-4075 2675);
DISPLAY INVISIBLE (-4075 2675);
FORCEPROP 1 LAST COMMENT_BODY TRUE
J 2
(-3700 2700);
DISPLAY 0.872340 (-3700 2700);
PAINT GREEN (-3700 2700);
DISPLAY INVISIBLE (-3700 2700);
FORCEPROP 2 LAST PATH I17
J 0
(-3700 2875);
DISPLAY 1.021277 (-3700 2875);
DISPLAY INVISIBLE (-3700 2875);
FORCEADD OFFPAGE..2
(2700 3100);
FORCEPROP 2 LAST $XR1 103 
J 0
(2979 3100);
DISPLAY 0.638298 (2979 3100);
PAINT MONO (2979 3100);
FORCEPROP 2 LAST $XR0 53 
J 0
(2889 3100);
DISPLAY 0.638298 (2889 3100);
PAINT MONO (2889 3100);
FORCEPROP 2 LAST CDS_LIB standard
J 0
(2700 3100);
PAINT MONO (2700 3100);
DISPLAY INVISIBLE (2700 3100);
FORCEPROP 1 LAST OFFPAGE TRUE
J 0
(3025 2975);
DISPLAY 1.170213 (3025 2975);
PAINT GREEN (3025 2975);
DISPLAY INVISIBLE (3025 2975);
FORCEPROP 1 LAST COMMENT_BODY TRUE
J 0
(2655 3005);
DISPLAY 1.170213 (2655 3005);
PAINT GREEN (2655 3005);
DISPLAY INVISIBLE (2655 3005);
FORCEPROP 2 LAST PATH I170
J 0
(2875 3175);
DISPLAY 1.021277 (2875 3175);
DISPLAY INVISIBLE (2875 3175);
FORCEADD OFFPAGE..2
(2700 3150);
FORCEPROP 2 LAST $XR1 103 
J 0
(2979 3150);
DISPLAY 0.638298 (2979 3150);
PAINT MONO (2979 3150);
FORCEPROP 2 LAST $XR0 53 
J 0
(2889 3150);
DISPLAY 0.638298 (2889 3150);
PAINT MONO (2889 3150);
FORCEPROP 2 LAST CDS_LIB standard
J 0
(2700 3150);
PAINT MONO (2700 3150);
DISPLAY INVISIBLE (2700 3150);
FORCEPROP 1 LAST OFFPAGE TRUE
J 0
(3025 3025);
DISPLAY 1.170213 (3025 3025);
PAINT GREEN (3025 3025);
DISPLAY INVISIBLE (3025 3025);
FORCEPROP 1 LAST COMMENT_BODY TRUE
J 0
(2655 3055);
DISPLAY 1.170213 (2655 3055);
PAINT GREEN (2655 3055);
DISPLAY INVISIBLE (2655 3055);
FORCEPROP 2 LAST PATH I171
J 0
(2875 3225);
DISPLAY 1.021277 (2875 3225);
DISPLAY INVISIBLE (2875 3225);
FORCEADD OFFPAGE..2
(2700 4150);
FORCEPROP 2 LAST $XR1 103 
J 0
(2979 4150);
DISPLAY 0.638298 (2979 4150);
PAINT MONO (2979 4150);
FORCEPROP 2 LAST $XR0 53 
J 0
(2889 4150);
DISPLAY 0.638298 (2889 4150);
PAINT MONO (2889 4150);
FORCEPROP 2 LAST CDS_LIB standard
J 0
(2700 4150);
PAINT MONO (2700 4150);
DISPLAY INVISIBLE (2700 4150);
FORCEPROP 1 LAST OFFPAGE TRUE
J 0
(3025 4025);
DISPLAY 1.170213 (3025 4025);
PAINT GREEN (3025 4025);
DISPLAY INVISIBLE (3025 4025);
FORCEPROP 1 LAST COMMENT_BODY TRUE
J 0
(2655 4055);
DISPLAY 1.170213 (2655 4055);
PAINT GREEN (2655 4055);
DISPLAY INVISIBLE (2655 4055);
FORCEPROP 2 LAST PATH I172
J 0
(2875 4225);
DISPLAY 1.021277 (2875 4225);
DISPLAY INVISIBLE (2875 4225);
FORCEADD TAP..1
(1575 4175);
FORCEPROP 3 LASTPIN (1525 4175) SIG_NAME M_C_CPU1_SA_DQS_DP<9>
J 0
(1535 4185);
DISPLAY 0.659574 (1535 4185);
PAINT MONO (1535 4185);
DISPLAY INVISIBLE (1535 4185);
FORCEPROP 1 LASTPIN (1525 4175) BN 9
J 0
(1513 4183);
DISPLAY 0.680851 (1513 4183);
PAINT GREEN (1513 4183);
FORCEPROP 2 LAST CDS_LIB standard
J 0
(1575 4175);
DISPLAY INVISIBLE (1575 4175);
FORCEPROP 1 LAST BODY_TYPE PLUMBING
J 0
(1575 4225);
DISPLAY 0.872340 (1575 4225);
PAINT GREEN (1575 4225);
DISPLAY INVISIBLE (1575 4225);
FORCEPROP 1 LAST HDL_TAP TRUE
J 0
(1900 4050);
DISPLAY 0.872340 (1900 4050);
DISPLAY INVISIBLE (1900 4050);
FORCEPROP 1 LAST PATH I173
J 0
(1573 4175);
DISPLAY 0.872340 (1573 4175);
PAINT GREEN (1573 4175);
DISPLAY INVISIBLE (1573 4175);
FORCEADD TAP..1
(1750 4125);
FORCEPROP 3 LASTPIN (1700 4125) SIG_NAME M_C_CPU1_SA_DQS_DN<9>
J 0
(1710 4135);
DISPLAY 0.659574 (1710 4135);
PAINT MONO (1710 4135);
DISPLAY INVISIBLE (1710 4135);
FORCEPROP 1 LASTPIN (1700 4125) BN 9
J 0
(1688 4133);
DISPLAY 0.680851 (1688 4133);
PAINT GREEN (1688 4133);
FORCEPROP 2 LAST CDS_LIB standard
J 0
(1750 4125);
DISPLAY INVISIBLE (1750 4125);
FORCEPROP 1 LAST BODY_TYPE PLUMBING
J 0
(1750 4175);
DISPLAY 0.872340 (1750 4175);
PAINT GREEN (1750 4175);
DISPLAY INVISIBLE (1750 4175);
FORCEPROP 1 LAST HDL_TAP TRUE
J 0
(2075 4000);
DISPLAY 0.872340 (2075 4000);
DISPLAY INVISIBLE (2075 4000);
FORCEPROP 1 LAST PATH I174
J 0
(1748 4125);
DISPLAY 0.872340 (1748 4125);
PAINT GREEN (1748 4125);
DISPLAY INVISIBLE (1748 4125);
FORCEADD OFFPAGE..2
(2700 4200);
FORCEPROP 2 LAST $XR1 103 
J 0
(2979 4200);
DISPLAY 0.638298 (2979 4200);
PAINT MONO (2979 4200);
FORCEPROP 2 LAST $XR0 53 
J 0
(2889 4200);
DISPLAY 0.638298 (2889 4200);
PAINT MONO (2889 4200);
FORCEPROP 2 LAST CDS_LIB standard
J 0
(2700 4200);
PAINT MONO (2700 4200);
DISPLAY INVISIBLE (2700 4200);
FORCEPROP 1 LAST OFFPAGE TRUE
J 0
(3025 4075);
DISPLAY 1.170213 (3025 4075);
PAINT GREEN (3025 4075);
DISPLAY INVISIBLE (3025 4075);
FORCEPROP 1 LAST COMMENT_BODY TRUE
J 0
(2655 4105);
DISPLAY 1.170213 (2655 4105);
PAINT GREEN (2655 4105);
DISPLAY INVISIBLE (2655 4105);
FORCEPROP 2 LAST PATH I175
J 0
(2875 4275);
DISPLAY 1.021277 (2875 4275);
DISPLAY INVISIBLE (2875 4275);
FORCEADD VCC_CORE..1
(3250 4725);
FORCEPROP 3 LASTPIN (3250 4675) SIG_NAME P12V_S3_AUX_CPU1_NVDIMM\g
J 0
(3260 4685);
DISPLAY 0.659574 (3260 4685);
PAINT MONO (3260 4685);
DISPLAY INVISIBLE (3260 4685);
FORCEPROP 1 LAST HDL_POWER P12V_S3_AUX_CPU1_NVDIMM
J 1
(3250 4775);
DISPLAY 1.148936 (3250 4775);
PAINT GREEN (3250 4775);
FORCEPROP 2 LAST CDS_LIB logical_power
J 0
(3250 4725);
PAINT MONO (3250 4725);
DISPLAY INVISIBLE (3250 4725);
FORCEPROP 1 LAST PATH I176
J 0
(3300 4750);
DISPLAY 0.872340 (3300 4750);
PAINT AQUA (3300 4750);
DISPLAY INVISIBLE (3300 4750);
FORCEADD UNIVERSAL_GND..1
(4950 475);
FORCEPROP 3 LASTPIN (4950 525) SIG_NAME GND\g
J 0
(4960 535);
DISPLAY 0.659574 (4960 535);
PAINT MONO (4960 535);
DISPLAY INVISIBLE (4960 535);
FORCEPROP 1 LAST PATH I177
J 0
(5025 475);
DISPLAY 0.872340 (5025 475);
PAINT AQUA (5025 475);
DISPLAY INVISIBLE (5025 475);
FORCEPROP 1 LAST HDL_POWER GND
J 1
(4975 400);
DISPLAY 0.872340 (4975 400);
PAINT GREEN (4975 400);
DISPLAY INVISIBLE (4975 400);
FORCEPROP 2 LAST CDS_LIB logical_power
J 0
(4950 475);
PAINT MONO (4950 475);
DISPLAY INVISIBLE (4950 475);
FORCEADD SCONN288_ADR50017P130CC..2
(675 3175);
FORCEPROP 1 LAST PART_NUMBER DFHST8FS461
J 0
(82 4475);
DISPLAY 0.723404 (82 4475);
PAINT GREEN (82 4475);
DISPLAY INVISIBLE (82 4475);
FORCEPROP 2 LAST VALUE SCONN288_ADR50017-P130CC
J 0
(93 4578);
DISPLAY 1.021277 (93 4578);
FORCEPROP 1 LAST MATERIAL IO
J 0
(82 4348);
DISPLAY 0.723404 (82 4348);
PAINT GREEN (82 4348);
FORCEPROP 2 LAST PART_TYPE SMLF
J 0
(93 4628);
DISPLAY 1.021277 (93 4628);
FORCEPROP 1 LAST LOCATION J21
J 0
(75 4525);
DISPLAY 0.723404 (75 4525);
PAINT GREEN (75 4525);
FORCEPROP 0 LASTPIN (1425 3225) $PN 12
J 0
(1435 3235);
DISPLAY 0.680851 (1435 3235);
PAINT MONO (1435 3235);
FORCEPROP 0 LASTPIN (1425 3275) $PN 11
J 0
(1435 3285);
DISPLAY 0.680851 (1435 3285);
PAINT MONO (1435 3285);
FORCEPROP 0 LASTPIN (1425 2175) $PN 105
J 0
(1435 2185);
DISPLAY 0.680851 (1435 2185);
PAINT MONO (1435 2185);
FORCEPROP 0 LASTPIN (1425 2225) $PN 104
J 0
(1435 2235);
DISPLAY 0.680851 (1435 2235);
PAINT MONO (1435 2235);
FORCEPROP 0 LASTPIN (1425 3325) $PN 23
J 0
(1435 3335);
DISPLAY 0.680851 (1435 3335);
PAINT MONO (1435 3335);
FORCEPROP 0 LASTPIN (1425 3375) $PN 22
J 0
(1435 3385);
DISPLAY 0.680851 (1435 3385);
PAINT MONO (1435 3385);
FORCEPROP 0 LASTPIN (1425 2275) $PN 116
J 0
(1435 2285);
DISPLAY 0.680851 (1435 2285);
PAINT MONO (1435 2285);
FORCEPROP 0 LASTPIN (1425 2325) $PN 115
J 0
(1435 2335);
DISPLAY 0.680851 (1435 2335);
PAINT MONO (1435 2335);
FORCEPROP 0 LASTPIN (1425 3425) $PN 34
J 0
(1435 3435);
DISPLAY 0.680851 (1435 3435);
PAINT MONO (1435 3435);
FORCEPROP 0 LASTPIN (1425 3475) $PN 33
J 0
(1435 3485);
DISPLAY 0.680851 (1435 3485);
PAINT MONO (1435 3485);
FORCEPROP 0 LASTPIN (1425 2375) $PN 127
J 0
(1435 2385);
DISPLAY 0.680851 (1435 2385);
PAINT MONO (1435 2385);
FORCEPROP 0 LASTPIN (1425 2425) $PN 126
J 0
(1435 2435);
DISPLAY 0.680851 (1435 2435);
PAINT MONO (1435 2435);
FORCEPROP 0 LASTPIN (1425 3525) $PN 45
J 0
(1435 3535);
DISPLAY 0.680851 (1435 3535);
PAINT MONO (1435 3535);
FORCEPROP 0 LASTPIN (1425 3575) $PN 44
J 0
(1435 3585);
DISPLAY 0.680851 (1435 3585);
PAINT MONO (1435 3585);
FORCEPROP 0 LASTPIN (1425 2475) $PN 138
J 0
(1435 2485);
DISPLAY 0.680851 (1435 2485);
PAINT MONO (1435 2485);
FORCEPROP 0 LASTPIN (1425 2525) $PN 137
J 0
(1435 2535);
DISPLAY 0.680851 (1435 2535);
PAINT MONO (1435 2535);
FORCEPROP 0 LASTPIN (1425 3625) $PN 56
J 0
(1435 3635);
DISPLAY 0.680851 (1435 3635);
PAINT MONO (1435 3635);
FORCEPROP 0 LASTPIN (1425 3675) $PN 55
J 0
(1435 3685);
DISPLAY 0.680851 (1435 3685);
PAINT MONO (1435 3685);
FORCEPROP 0 LASTPIN (1425 2575) $PN 238
J 0
(1435 2585);
DISPLAY 0.680851 (1435 2585);
PAINT MONO (1435 2585);
FORCEPROP 0 LASTPIN (1425 2625) $PN 239
J 0
(1435 2635);
DISPLAY 0.680851 (1435 2635);
PAINT MONO (1435 2635);
FORCEPROP 0 LASTPIN (1425 3725) $PN 156
J 0
(1435 3735);
DISPLAY 0.680851 (1435 3735);
PAINT MONO (1435 3735);
FORCEPROP 0 LASTPIN (1425 3775) $PN 157
J 0
(1435 3785);
DISPLAY 0.680851 (1435 3785);
PAINT MONO (1435 3785);
FORCEPROP 0 LASTPIN (1425 2675) $PN 249
J 0
(1435 2685);
DISPLAY 0.680851 (1435 2685);
PAINT MONO (1435 2685);
FORCEPROP 0 LASTPIN (1425 2725) $PN 250
J 0
(1435 2735);
DISPLAY 0.680851 (1435 2735);
PAINT MONO (1435 2735);
FORCEPROP 0 LASTPIN (1425 3825) $PN 167
J 0
(1435 3835);
DISPLAY 0.680851 (1435 3835);
PAINT MONO (1435 3835);
FORCEPROP 0 LASTPIN (1425 3875) $PN 168
J 0
(1435 3885);
DISPLAY 0.680851 (1435 3885);
PAINT MONO (1435 3885);
FORCEPROP 0 LASTPIN (1425 2775) $PN 260
J 0
(1435 2785);
DISPLAY 0.680851 (1435 2785);
PAINT MONO (1435 2785);
FORCEPROP 0 LASTPIN (1425 2825) $PN 261
J 0
(1435 2835);
DISPLAY 0.680851 (1435 2835);
PAINT MONO (1435 2835);
FORCEPROP 0 LASTPIN (1425 3925) $PN 178
J 0
(1435 3935);
DISPLAY 0.680851 (1435 3935);
PAINT MONO (1435 3935);
FORCEPROP 0 LASTPIN (1425 3975) $PN 179
J 0
(1435 3985);
DISPLAY 0.680851 (1435 3985);
PAINT MONO (1435 3985);
FORCEPROP 0 LASTPIN (1425 2875) $PN 271
J 0
(1435 2885);
DISPLAY 0.680851 (1435 2885);
PAINT MONO (1435 2885);
FORCEPROP 0 LASTPIN (1425 2925) $PN 272
J 0
(1435 2935);
DISPLAY 0.680851 (1435 2935);
PAINT MONO (1435 2935);
FORCEPROP 0 LASTPIN (1425 4025) $PN 189
J 0
(1435 4035);
DISPLAY 0.680851 (1435 4035);
PAINT MONO (1435 4035);
FORCEPROP 0 LASTPIN (1425 4075) $PN 190
J 0
(1435 4085);
DISPLAY 0.680851 (1435 4085);
PAINT MONO (1435 4085);
FORCEPROP 0 LASTPIN (1425 2975) $PN 282
J 0
(1435 2985);
DISPLAY 0.680851 (1435 2985);
PAINT MONO (1435 2985);
FORCEPROP 0 LASTPIN (1425 3025) $PN 283
J 0
(1435 3035);
DISPLAY 0.680851 (1435 3035);
PAINT MONO (1435 3035);
FORCEPROP 0 LASTPIN (1425 4125) $PN 200
J 0
(1435 4135);
DISPLAY 0.680851 (1435 4135);
PAINT MONO (1435 4135);
FORCEPROP 0 LASTPIN (1425 4175) $PN 201
J 0
(1435 4185);
DISPLAY 0.680851 (1435 4185);
PAINT MONO (1435 4185);
FORCEPROP 0 LASTPIN (1425 3075) $PN 94
J 0
(1435 3085);
DISPLAY 0.680851 (1435 3085);
PAINT MONO (1435 3085);
FORCEPROP 0 LASTPIN (1425 3125) $PN 93
J 0
(1435 3135);
DISPLAY 0.680851 (1435 3135);
PAINT MONO (1435 3135);
FORCEPROP 1 LAST CDS_LMAN_SYM_OUTLINE -600,1150,600,-1150
J 0
(675 3175);
DISPLAY 0.468085 (675 3175);
PAINT GREEN (675 3175);
DISPLAY INVISIBLE (675 3175);
FORCEPROP 2 LAST CDS_LIB pure_quanta
J 0
(675 3175);
DISPLAY INVISIBLE (675 3175);
FORCEPROP 1 LAST NEEDS_NO_SIZE TRUE
J 0
(675 3175);
DISPLAY 0.723404 (675 3175);
PAINT GREEN (675 3175);
DISPLAY INVISIBLE (675 3175);
FORCEPROP 1 LAST PATH I178
J 0
(675 3175);
DISPLAY 0.723404 (675 3175);
PAINT GREEN (675 3175);
DISPLAY INVISIBLE (675 3175);
FORCEPROP 0 LAST $SEC 2
J 0
(100 4700);
DISPLAY 0.680851 (100 4700);
PAINT MONO (100 4700);
DISPLAY INVISIBLE (100 4700);
FORCEPROP 0 LAST CDS_SEC 2
J 0
(100 4700);
DISPLAY 1.021277 (100 4700);
DISPLAY INVISIBLE (100 4700);
FORCEADD OFFPAGE..1
(-2575 1400);
FORCEPROP 2 LAST $XR7 105 
J 0
(-3607 1400);
DISPLAY 0.638298 (-3607 1400);
PAINT MONO (-3607 1400);
FORCEPROP 2 LAST $XR6 104 
J 0
(-3487 1400);
DISPLAY 0.638298 (-3487 1400);
PAINT MONO (-3487 1400);
FORCEPROP 2 LAST $XR5 103 
J 0
(-3367 1400);
DISPLAY 0.638298 (-3367 1400);
PAINT MONO (-3367 1400);
FORCEPROP 2 LAST $XR4 101 
J 0
(-3247 1400);
DISPLAY 0.638298 (-3247 1400);
PAINT MONO (-3247 1400);
FORCEPROP 2 LAST $XR3 100 
J 0
(-3127 1400);
DISPLAY 0.638298 (-3127 1400);
PAINT MONO (-3127 1400);
FORCEPROP 2 LAST $XR2 99 
J 0
(-3007 1400);
DISPLAY 0.638298 (-3007 1400);
PAINT MONO (-3007 1400);
FORCEPROP 2 LAST $XR1 98 
J 0
(-2917 1400);
DISPLAY 0.638298 (-2917 1400);
PAINT MONO (-2917 1400);
FORCEPROP 2 LAST $XR0 230 
J 0
(-2827 1400);
DISPLAY 0.638298 (-2827 1400);
PAINT MONO (-2827 1400);
FORCEPROP 2 LAST CDS_LIB standard
J 2
(-2575 1400);
DISPLAY INVISIBLE (-2575 1400);
FORCEPROP 1 LAST OFFPAGE TRUE
J 0
(-2250 1275);
DISPLAY 0.872340 (-2250 1275);
DISPLAY INVISIBLE (-2250 1275);
FORCEPROP 1 LAST COMMENT_BODY TRUE
J 0
(-2450 1300);
DISPLAY 0.872340 (-2450 1300);
PAINT GREEN (-2450 1300);
DISPLAY INVISIBLE (-2450 1300);
FORCEPROP 2 LAST PATH I179
J 2
(-2750 1475);
DISPLAY 1.021277 (-2750 1475);
DISPLAY INVISIBLE (-2750 1475);
FORCEADD OFFPAGE..1
(-3750 3025);
FORCEPROP 2 LAST $XR0 53 
J 0
(-3971 3025);
DISPLAY 0.638298 (-3971 3025);
PAINT MONO (-3971 3025);
FORCEPROP 2 LAST CDS_LIB standard
J 0
(-3750 3025);
PAINT MONO (-3750 3025);
DISPLAY INVISIBLE (-3750 3025);
FORCEPROP 1 LAST OFFPAGE TRUE
J 0
(-3425 2900);
DISPLAY 0.872340 (-3425 2900);
DISPLAY INVISIBLE (-3425 2900);
FORCEPROP 1 LAST COMMENT_BODY TRUE
J 0
(-3625 2925);
DISPLAY 0.872340 (-3625 2925);
PAINT GREEN (-3625 2925);
DISPLAY INVISIBLE (-3625 2925);
FORCEPROP 2 LAST PATH I18
J 0
(-3700 3100);
DISPLAY 1.021277 (-3700 3100);
DISPLAY INVISIBLE (-3700 3100);
FORCEADD Q_RES..1
(-3825 1450);
FORCEPROP 1 LAST PART_NUMBER CS04992FB07
J 0
(-3725 1425);
DISPLAY 0.404255 (-3725 1425);
DISPLAY INVISIBLE (-3725 1425);
FORCEPROP 1 LAST VALUE 49.9
J 2
(-3600 1450);
DISPLAY 0.510638 (-3600 1450);
FORCEPROP 1 LAST MATERIAL CHIP
J 0
(-4000 1425);
DISPLAY 0.404255 (-4000 1425);
FORCEPROP 1 LAST $LOCATION R3895
J 0
(-4075 1450);
DISPLAY 0.638298 (-4075 1450);
FORCEPROP 1 LASTPIN (-3925 1450) $PN 1
J 0
(-3913 1462);
DISPLAY 0.787234 (-3913 1462);
PAINT MONO (-3913 1462);
FORCEPROP 1 LASTPIN (-3725 1450) $PN 2
J 0
(-3763 1462);
DISPLAY 0.787234 (-3763 1462);
PAINT MONO (-3763 1462);
FORCEPROP 2 LAST CDS_LIB pure_quanta
J 0
(-3825 1450);
DISPLAY INVISIBLE (-3825 1450);
FORCEPROP 1 LAST PACK_TYPE 0402LF
J 0
(-3525 1450);
DISPLAY 0.510638 (-3525 1450);
DISPLAY INVISIBLE (-3525 1450);
FORCEPROP 1 LAST TOLERANCE 1%
J 0
(-3600 1450);
DISPLAY 0.510638 (-3600 1450);
DISPLAY INVISIBLE (-3600 1450);
FORCEPROP 1 LAST WATTAGE 1/16W
J 2
(-3525 1400);
DISPLAY 0.404255 (-3525 1400);
DISPLAY INVISIBLE (-3525 1400);
FORCEPROP 1 LAST PATH I180
J 0
(-3875 1600);
DISPLAY 0.978723 (-3875 1600);
PAINT WHITE (-3875 1600);
DISPLAY INVISIBLE (-3875 1600);
FORCEPROP 0 LAST CDS_LOCATION R3895
J 0
(-3975 1500);
DISPLAY 1.021277 (-3975 1500);
DISPLAY INVISIBLE (-3975 1500);
FORCEPROP 0 LAST $SEC 1
J 0
(-3975 1500);
DISPLAY 0.680851 (-3975 1500);
PAINT MONO (-3975 1500);
DISPLAY INVISIBLE (-3975 1500);
FORCEPROP 0 LAST CDS_SEC 1
J 0
(-3975 1500);
DISPLAY 1.021277 (-3975 1500);
DISPLAY INVISIBLE (-3975 1500);
FORCEADD OFFPAGE..1
(-3750 2925);
FORCEPROP 2 LAST $XR0 53 
J 0
(-3971 2925);
DISPLAY 0.638298 (-3971 2925);
PAINT MONO (-3971 2925);
FORCEPROP 2 LAST CDS_LIB standard
J 0
(-3750 2925);
PAINT MONO (-3750 2925);
DISPLAY INVISIBLE (-3750 2925);
FORCEPROP 1 LAST OFFPAGE TRUE
J 0
(-3425 2800);
DISPLAY 0.872340 (-3425 2800);
DISPLAY INVISIBLE (-3425 2800);
FORCEPROP 1 LAST COMMENT_BODY TRUE
J 0
(-3625 2825);
DISPLAY 0.872340 (-3625 2825);
PAINT GREEN (-3625 2825);
DISPLAY INVISIBLE (-3625 2825);
FORCEPROP 2 LAST PATH I19
J 0
(-3700 3000);
DISPLAY 1.021277 (-3700 3000);
DISPLAY INVISIBLE (-3700 3000);
FORCEADD Q_RES..2
(-2600 25);
FORCEPROP 1 LAST PART_NUMBER CS35492FB03
J 0
(-2560 -100);
DISPLAY 0.978723 (-2560 -100);
DISPLAY INVISIBLE (-2560 -100);
FORCEPROP 1 LAST VALUE 54.9K
J 0
(-2555 100);
DISPLAY 0.978723 (-2555 100);
FORCEPROP 1 LAST TOLERANCE 1%
J 0
(-2555 50);
DISPLAY 0.978723 (-2555 50);
FORCEPROP 1 LAST WATTAGE 1/16W
J 0
(-2560 0);
DISPLAY 0.978723 (-2560 0);
FORCEPROP 1 LAST MATERIAL CHIP
J 0
(-2560 -50);
DISPLAY 0.978723 (-2560 -50);
FORCEPROP 1 LAST PACK_TYPE 0402LF
J 0
(-2560 -150);
DISPLAY 0.978723 (-2560 -150);
FORCEPROP 1 LAST $LOCATION R46
J 0
(-2555 150);
DISPLAY 0.978723 (-2555 150);
FORCEPROP 1 LASTPIN (-2600 125) $PN 1
J 0
(-2595 87);
DISPLAY 0.787234 (-2595 87);
FORCEPROP 1 LASTPIN (-2600 -75) $PN 2
J 0
(-2595 -65);
DISPLAY 0.787234 (-2595 -65);
FORCEPROP 2 LAST CDS_LIB pure_quanta
J 0
(-2600 25);
PAINT MONO (-2600 25);
DISPLAY INVISIBLE (-2600 25);
FORCEPROP 1 LAST PATH I2
J 0
(-2550 200);
DISPLAY 0.978723 (-2550 200);
PAINT WHITE (-2550 200);
DISPLAY INVISIBLE (-2550 200);
FORCEPROP 1 LAST $LOCATION R46
J 0
(-2550 250);
DISPLAY 1.021277 (-2550 250);
DISPLAY INVISIBLE (-2550 250);
FORCEPROP 2 LAST CDS_LOCATION R46
J 0
(-2550 250);
DISPLAY 1.021277 (-2550 250);
DISPLAY INVISIBLE (-2550 250);
FORCEPROP 2 LAST $SEC 1
J 0
(-2550 250);
DISPLAY 0.680851 (-2550 250);
PAINT MONO (-2550 250);
DISPLAY INVISIBLE (-2550 250);
FORCEPROP 2 LAST CDS_SEC 1
J 0
(-2550 250);
DISPLAY 1.021277 (-2550 250);
DISPLAY INVISIBLE (-2550 250);
FORCEADD OFFPAGE..1
(-3750 2875);
FORCEPROP 2 LAST $XR0 53 
J 0
(-3971 2875);
DISPLAY 0.638298 (-3971 2875);
PAINT MONO (-3971 2875);
FORCEPROP 2 LAST CDS_LIB standard
J 0
(-3750 2875);
PAINT MONO (-3750 2875);
DISPLAY INVISIBLE (-3750 2875);
FORCEPROP 1 LAST OFFPAGE TRUE
J 0
(-3425 2750);
DISPLAY 0.872340 (-3425 2750);
DISPLAY INVISIBLE (-3425 2750);
FORCEPROP 1 LAST COMMENT_BODY TRUE
J 0
(-3625 2775);
DISPLAY 0.872340 (-3625 2775);
PAINT GREEN (-3625 2775);
DISPLAY INVISIBLE (-3625 2775);
FORCEPROP 2 LAST PATH I20
J 0
(-3700 2950);
DISPLAY 1.021277 (-3700 2950);
DISPLAY INVISIBLE (-3700 2950);
FORCEADD OFFPAGE..1
(-3750 3075);
FORCEPROP 2 LAST $XR0 53 
J 0
(-3971 3075);
DISPLAY 0.638298 (-3971 3075);
PAINT MONO (-3971 3075);
FORCEPROP 2 LAST CDS_LIB standard
J 0
(-3750 3075);
PAINT MONO (-3750 3075);
DISPLAY INVISIBLE (-3750 3075);
FORCEPROP 1 LAST OFFPAGE TRUE
J 0
(-3425 2950);
DISPLAY 0.872340 (-3425 2950);
DISPLAY INVISIBLE (-3425 2950);
FORCEPROP 1 LAST COMMENT_BODY TRUE
J 0
(-3625 2975);
DISPLAY 0.872340 (-3625 2975);
PAINT GREEN (-3625 2975);
DISPLAY INVISIBLE (-3625 2975);
FORCEPROP 2 LAST PATH I21
J 0
(-3700 3150);
DISPLAY 1.021277 (-3700 3150);
DISPLAY INVISIBLE (-3700 3150);
FORCEADD OFFPAGE..1
(-3750 3375);
FORCEPROP 2 LAST $XR1 103 
J 0
(-4091 3375);
DISPLAY 0.638298 (-4091 3375);
PAINT MONO (-4091 3375);
FORCEPROP 2 LAST $XR0 53 
J 0
(-3971 3375);
DISPLAY 0.638298 (-3971 3375);
PAINT MONO (-3971 3375);
FORCEPROP 2 LAST CDS_LIB standard
J 0
(-3750 3375);
PAINT MONO (-3750 3375);
DISPLAY INVISIBLE (-3750 3375);
FORCEPROP 1 LAST OFFPAGE TRUE
J 0
(-3425 3250);
DISPLAY 0.872340 (-3425 3250);
DISPLAY INVISIBLE (-3425 3250);
FORCEPROP 1 LAST COMMENT_BODY TRUE
J 0
(-3625 3275);
DISPLAY 0.872340 (-3625 3275);
PAINT GREEN (-3625 3275);
DISPLAY INVISIBLE (-3625 3275);
FORCEPROP 2 LAST PATH I22
J 0
(-3700 3450);
DISPLAY 1.021277 (-3700 3450);
DISPLAY INVISIBLE (-3700 3450);
FORCEADD OFFPAGE..1
(-3750 3325);
FORCEPROP 2 LAST $XR1 103 
J 0
(-4091 3325);
DISPLAY 0.638298 (-4091 3325);
PAINT MONO (-4091 3325);
FORCEPROP 2 LAST $XR0 53 
J 0
(-3971 3325);
DISPLAY 0.638298 (-3971 3325);
PAINT MONO (-3971 3325);
FORCEPROP 2 LAST CDS_LIB standard
J 0
(-3750 3325);
PAINT MONO (-3750 3325);
DISPLAY INVISIBLE (-3750 3325);
FORCEPROP 1 LAST OFFPAGE TRUE
J 0
(-3425 3200);
DISPLAY 0.872340 (-3425 3200);
DISPLAY INVISIBLE (-3425 3200);
FORCEPROP 1 LAST COMMENT_BODY TRUE
J 0
(-3625 3225);
DISPLAY 0.872340 (-3625 3225);
PAINT GREEN (-3625 3225);
DISPLAY INVISIBLE (-3625 3225);
FORCEPROP 2 LAST PATH I23
J 0
(-3700 3400);
DISPLAY 1.021277 (-3700 3400);
DISPLAY INVISIBLE (-3700 3400);
FORCEADD OFFPAGE..1
(-3750 3225);
FORCEPROP 2 LAST $XR0 53 
J 0
(-3971 3225);
DISPLAY 0.638298 (-3971 3225);
PAINT MONO (-3971 3225);
FORCEPROP 2 LAST CDS_LIB standard
J 0
(-3750 3225);
PAINT MONO (-3750 3225);
DISPLAY INVISIBLE (-3750 3225);
FORCEPROP 1 LAST OFFPAGE TRUE
J 0
(-3425 3100);
DISPLAY 0.872340 (-3425 3100);
DISPLAY INVISIBLE (-3425 3100);
FORCEPROP 1 LAST COMMENT_BODY TRUE
J 0
(-3625 3125);
DISPLAY 0.872340 (-3625 3125);
PAINT GREEN (-3625 3125);
DISPLAY INVISIBLE (-3625 3125);
FORCEPROP 2 LAST PATH I24
J 0
(-3700 3300);
DISPLAY 1.021277 (-3700 3300);
DISPLAY INVISIBLE (-3700 3300);
FORCEADD OFFPAGE..1
(-3750 3175);
FORCEPROP 2 LAST $XR0 53 
J 0
(-3971 3175);
DISPLAY 0.638298 (-3971 3175);
PAINT MONO (-3971 3175);
FORCEPROP 2 LAST CDS_LIB standard
J 0
(-3750 3175);
PAINT MONO (-3750 3175);
DISPLAY INVISIBLE (-3750 3175);
FORCEPROP 1 LAST OFFPAGE TRUE
J 0
(-3425 3050);
DISPLAY 0.872340 (-3425 3050);
DISPLAY INVISIBLE (-3425 3050);
FORCEPROP 1 LAST COMMENT_BODY TRUE
J 0
(-3625 3075);
DISPLAY 0.872340 (-3625 3075);
PAINT GREEN (-3625 3075);
DISPLAY INVISIBLE (-3625 3075);
FORCEPROP 2 LAST PATH I25
J 0
(-3700 3250);
DISPLAY 1.021277 (-3700 3250);
DISPLAY INVISIBLE (-3700 3250);
FORCEADD OFFPAGE..1
(-3750 3800);
FORCEPROP 2 LAST $XR1 103 
J 0
(-4091 3800);
DISPLAY 0.638298 (-4091 3800);
PAINT MONO (-4091 3800);
FORCEPROP 2 LAST $XR0 53 
J 0
(-3971 3800);
DISPLAY 0.638298 (-3971 3800);
PAINT MONO (-3971 3800);
FORCEPROP 2 LAST CDS_LIB standard
J 0
(-3750 3800);
PAINT MONO (-3750 3800);
DISPLAY INVISIBLE (-3750 3800);
FORCEPROP 1 LAST OFFPAGE TRUE
J 0
(-3425 3675);
DISPLAY 0.872340 (-3425 3675);
DISPLAY INVISIBLE (-3425 3675);
FORCEPROP 1 LAST COMMENT_BODY TRUE
J 0
(-3625 3700);
DISPLAY 0.872340 (-3625 3700);
PAINT GREEN (-3625 3700);
DISPLAY INVISIBLE (-3625 3700);
FORCEPROP 2 LAST PATH I26
J 0
(-3700 3875);
DISPLAY 1.021277 (-3700 3875);
DISPLAY INVISIBLE (-3700 3875);
FORCEADD TAP..1
R 2
(-2825 2125);
FORCEPROP 3 LASTPIN (-2775 2125) SIG_NAME M_C_CPU1_SB_CB<3>
J 0
(-2765 2135);
DISPLAY 0.659574 (-2765 2135);
PAINT MONO (-2765 2135);
DISPLAY INVISIBLE (-2765 2135);
FORCEPROP 1 LASTPIN (-2775 2125) BN 3
J 2
(-2763 2133);
DISPLAY 0.680851 (-2763 2133);
PAINT GREEN (-2763 2133);
FORCEPROP 2 LAST CDS_LIB standard
J 0
(-2825 2125);
DISPLAY INVISIBLE (-2825 2125);
FORCEPROP 1 LAST BODY_TYPE PLUMBING
J 2
(-2825 2175);
DISPLAY 0.872340 (-2825 2175);
PAINT GREEN (-2825 2175);
DISPLAY INVISIBLE (-2825 2175);
FORCEPROP 1 LAST HDL_TAP TRUE
J 2
(-3150 2000);
DISPLAY 0.872340 (-3150 2000);
DISPLAY INVISIBLE (-3150 2000);
FORCEPROP 1 LAST PATH I27
J 2
(-2823 2125);
DISPLAY 0.872340 (-2823 2125);
PAINT GREEN (-2823 2125);
DISPLAY INVISIBLE (-2823 2125);
FORCEADD TAP..1
R 2
(-2825 2075);
FORCEPROP 3 LASTPIN (-2775 2075) SIG_NAME M_C_CPU1_SB_CB<2>
J 0
(-2765 2085);
DISPLAY 0.659574 (-2765 2085);
PAINT MONO (-2765 2085);
DISPLAY INVISIBLE (-2765 2085);
FORCEPROP 1 LASTPIN (-2775 2075) BN 2
J 2
(-2763 2083);
DISPLAY 0.680851 (-2763 2083);
PAINT GREEN (-2763 2083);
FORCEPROP 2 LAST CDS_LIB standard
J 0
(-2825 2075);
DISPLAY INVISIBLE (-2825 2075);
FORCEPROP 1 LAST BODY_TYPE PLUMBING
J 2
(-2825 2125);
DISPLAY 0.872340 (-2825 2125);
PAINT GREEN (-2825 2125);
DISPLAY INVISIBLE (-2825 2125);
FORCEPROP 1 LAST HDL_TAP TRUE
J 2
(-3150 1950);
DISPLAY 0.872340 (-3150 1950);
DISPLAY INVISIBLE (-3150 1950);
FORCEPROP 1 LAST PATH I28
J 2
(-2823 2075);
DISPLAY 0.872340 (-2823 2075);
PAINT GREEN (-2823 2075);
DISPLAY INVISIBLE (-2823 2075);
FORCEADD TAP..1
R 2
(-2825 2175);
FORCEPROP 3 LASTPIN (-2775 2175) SIG_NAME M_C_CPU1_SB_CB<4>
J 0
(-2765 2185);
DISPLAY 0.659574 (-2765 2185);
PAINT MONO (-2765 2185);
DISPLAY INVISIBLE (-2765 2185);
FORCEPROP 1 LASTPIN (-2775 2175) BN 4
J 2
(-2763 2183);
DISPLAY 0.680851 (-2763 2183);
PAINT GREEN (-2763 2183);
FORCEPROP 2 LAST CDS_LIB standard
J 0
(-2825 2175);
DISPLAY INVISIBLE (-2825 2175);
FORCEPROP 1 LAST BODY_TYPE PLUMBING
J 2
(-2825 2225);
DISPLAY 0.872340 (-2825 2225);
PAINT GREEN (-2825 2225);
DISPLAY INVISIBLE (-2825 2225);
FORCEPROP 1 LAST HDL_TAP TRUE
J 2
(-3150 2050);
DISPLAY 0.872340 (-3150 2050);
DISPLAY INVISIBLE (-3150 2050);
FORCEPROP 1 LAST PATH I29
J 2
(-2823 2175);
DISPLAY 0.872340 (-2823 2175);
PAINT GREEN (-2823 2175);
DISPLAY INVISIBLE (-2823 2175);
FORCEADD OFFPAGE..2
R 2
(-3750 225);
FORCEPROP 2 LAST $XR0 102 
J 0
(-4005 225);
DISPLAY 0.638298 (-4005 225);
PAINT MONO (-4005 225);
FORCEPROP 2 LAST CDS_LIB standard
J 0
(-3750 225);
PAINT MONO (-3750 225);
DISPLAY INVISIBLE (-3750 225);
FORCEPROP 1 LAST OFFPAGE TRUE
J 2
(-4075 100);
DISPLAY 0.872340 (-4075 100);
DISPLAY INVISIBLE (-4075 100);
FORCEPROP 1 LAST COMMENT_BODY TRUE
J 2
(-3705 130);
DISPLAY 0.872340 (-3705 130);
PAINT GREEN (-3705 130);
DISPLAY INVISIBLE (-3705 130);
FORCEPROP 2 LAST PATH I3
J 0
(-3700 300);
DISPLAY 1.021277 (-3700 300);
DISPLAY INVISIBLE (-3700 300);
FORCEADD TAP..1
R 2
(-2825 2225);
FORCEPROP 3 LASTPIN (-2775 2225) SIG_NAME M_C_CPU1_SB_CB<5>
J 0
(-2765 2235);
DISPLAY 0.659574 (-2765 2235);
PAINT MONO (-2765 2235);
DISPLAY INVISIBLE (-2765 2235);
FORCEPROP 1 LASTPIN (-2775 2225) BN 5
J 2
(-2763 2233);
DISPLAY 0.680851 (-2763 2233);
PAINT GREEN (-2763 2233);
FORCEPROP 2 LAST CDS_LIB standard
J 0
(-2825 2225);
DISPLAY INVISIBLE (-2825 2225);
FORCEPROP 1 LAST BODY_TYPE PLUMBING
J 2
(-2825 2275);
DISPLAY 0.872340 (-2825 2275);
PAINT GREEN (-2825 2275);
DISPLAY INVISIBLE (-2825 2275);
FORCEPROP 1 LAST HDL_TAP TRUE
J 2
(-3150 2100);
DISPLAY 0.872340 (-3150 2100);
DISPLAY INVISIBLE (-3150 2100);
FORCEPROP 1 LAST PATH I30
J 2
(-2823 2225);
DISPLAY 0.872340 (-2823 2225);
PAINT GREEN (-2823 2225);
DISPLAY INVISIBLE (-2823 2225);
FORCEADD TAP..1
R 2
(-2825 2275);
FORCEPROP 3 LASTPIN (-2775 2275) SIG_NAME M_C_CPU1_SB_CB<6>
J 0
(-2765 2285);
DISPLAY 0.659574 (-2765 2285);
PAINT MONO (-2765 2285);
DISPLAY INVISIBLE (-2765 2285);
FORCEPROP 1 LASTPIN (-2775 2275) BN 6
J 2
(-2763 2283);
DISPLAY 0.680851 (-2763 2283);
PAINT GREEN (-2763 2283);
FORCEPROP 2 LAST CDS_LIB standard
J 0
(-2825 2275);
DISPLAY INVISIBLE (-2825 2275);
FORCEPROP 1 LAST BODY_TYPE PLUMBING
J 2
(-2825 2325);
DISPLAY 0.872340 (-2825 2325);
PAINT GREEN (-2825 2325);
DISPLAY INVISIBLE (-2825 2325);
FORCEPROP 1 LAST HDL_TAP TRUE
J 2
(-3150 2150);
DISPLAY 0.872340 (-3150 2150);
DISPLAY INVISIBLE (-3150 2150);
FORCEPROP 1 LAST PATH I31
J 2
(-2823 2275);
DISPLAY 0.872340 (-2823 2275);
PAINT GREEN (-2823 2275);
DISPLAY INVISIBLE (-2823 2275);
FORCEADD TAP..1
R 2
(-2825 2325);
FORCEPROP 3 LASTPIN (-2775 2325) SIG_NAME M_C_CPU1_SB_CB<7>
J 0
(-2765 2335);
DISPLAY 0.659574 (-2765 2335);
PAINT MONO (-2765 2335);
DISPLAY INVISIBLE (-2765 2335);
FORCEPROP 1 LASTPIN (-2775 2325) BN 7
J 2
(-2763 2333);
DISPLAY 0.680851 (-2763 2333);
PAINT GREEN (-2763 2333);
FORCEPROP 2 LAST CDS_LIB standard
J 0
(-2825 2325);
DISPLAY INVISIBLE (-2825 2325);
FORCEPROP 1 LAST BODY_TYPE PLUMBING
J 2
(-2825 2375);
DISPLAY 0.872340 (-2825 2375);
PAINT GREEN (-2825 2375);
DISPLAY INVISIBLE (-2825 2375);
FORCEPROP 1 LAST HDL_TAP TRUE
J 2
(-3150 2200);
DISPLAY 0.872340 (-3150 2200);
DISPLAY INVISIBLE (-3150 2200);
FORCEPROP 1 LAST PATH I32
J 2
(-2823 2325);
DISPLAY 0.872340 (-2823 2325);
PAINT GREEN (-2823 2325);
DISPLAY INVISIBLE (-2823 2325);
FORCEADD TAP..1
R 2
(-2825 2425);
FORCEPROP 3 LASTPIN (-2775 2425) SIG_NAME M_C_CPU1_SA_CB<0>
J 0
(-2765 2435);
DISPLAY 0.659574 (-2765 2435);
PAINT MONO (-2765 2435);
DISPLAY INVISIBLE (-2765 2435);
FORCEPROP 1 LASTPIN (-2775 2425) BN 0
J 2
(-2763 2433);
DISPLAY 0.680851 (-2763 2433);
PAINT GREEN (-2763 2433);
FORCEPROP 2 LAST CDS_LIB standard
J 0
(-2825 2425);
PAINT MONO (-2825 2425);
DISPLAY INVISIBLE (-2825 2425);
FORCEPROP 1 LAST BODY_TYPE PLUMBING
J 2
(-2825 2475);
DISPLAY 0.872340 (-2825 2475);
PAINT GREEN (-2825 2475);
DISPLAY INVISIBLE (-2825 2475);
FORCEPROP 1 LAST HDL_TAP TRUE
J 2
(-3150 2300);
DISPLAY 0.872340 (-3150 2300);
DISPLAY INVISIBLE (-3150 2300);
FORCEPROP 1 LAST PATH I33
J 2
(-2823 2425);
DISPLAY 0.872340 (-2823 2425);
PAINT GREEN (-2823 2425);
DISPLAY INVISIBLE (-2823 2425);
FORCEADD TAP..1
R 2
(-2825 2525);
FORCEPROP 3 LASTPIN (-2775 2525) SIG_NAME M_C_CPU1_SA_CB<2>
J 0
(-2765 2535);
DISPLAY 0.659574 (-2765 2535);
PAINT MONO (-2765 2535);
DISPLAY INVISIBLE (-2765 2535);
FORCEPROP 1 LASTPIN (-2775 2525) BN 2
J 2
(-2763 2533);
DISPLAY 0.680851 (-2763 2533);
PAINT GREEN (-2763 2533);
FORCEPROP 2 LAST CDS_LIB standard
J 0
(-2825 2525);
DISPLAY INVISIBLE (-2825 2525);
FORCEPROP 1 LAST BODY_TYPE PLUMBING
J 2
(-2825 2575);
DISPLAY 0.872340 (-2825 2575);
PAINT GREEN (-2825 2575);
DISPLAY INVISIBLE (-2825 2575);
FORCEPROP 1 LAST HDL_TAP TRUE
J 2
(-3150 2400);
DISPLAY 0.872340 (-3150 2400);
DISPLAY INVISIBLE (-3150 2400);
FORCEPROP 1 LAST PATH I34
J 2
(-2823 2525);
DISPLAY 0.872340 (-2823 2525);
PAINT GREEN (-2823 2525);
DISPLAY INVISIBLE (-2823 2525);
FORCEADD TAP..1
R 2
(-2825 2475);
FORCEPROP 3 LASTPIN (-2775 2475) SIG_NAME M_C_CPU1_SA_CB<1>
J 0
(-2765 2485);
DISPLAY 0.659574 (-2765 2485);
PAINT MONO (-2765 2485);
DISPLAY INVISIBLE (-2765 2485);
FORCEPROP 1 LASTPIN (-2775 2475) BN 1
J 2
(-2763 2483);
DISPLAY 0.680851 (-2763 2483);
PAINT GREEN (-2763 2483);
FORCEPROP 2 LAST CDS_LIB standard
J 0
(-2825 2475);
DISPLAY INVISIBLE (-2825 2475);
FORCEPROP 1 LAST BODY_TYPE PLUMBING
J 2
(-2825 2525);
DISPLAY 0.872340 (-2825 2525);
PAINT GREEN (-2825 2525);
DISPLAY INVISIBLE (-2825 2525);
FORCEPROP 1 LAST HDL_TAP TRUE
J 2
(-3150 2350);
DISPLAY 0.872340 (-3150 2350);
DISPLAY INVISIBLE (-3150 2350);
FORCEPROP 1 LAST PATH I35
J 2
(-2823 2475);
DISPLAY 0.872340 (-2823 2475);
PAINT GREEN (-2823 2475);
DISPLAY INVISIBLE (-2823 2475);
FORCEADD TAP..1
R 2
(-2825 2575);
FORCEPROP 3 LASTPIN (-2775 2575) SIG_NAME M_C_CPU1_SA_CB<3>
J 0
(-2765 2585);
DISPLAY 0.659574 (-2765 2585);
PAINT MONO (-2765 2585);
DISPLAY INVISIBLE (-2765 2585);
FORCEPROP 1 LASTPIN (-2775 2575) BN 3
J 2
(-2763 2583);
DISPLAY 0.680851 (-2763 2583);
PAINT GREEN (-2763 2583);
FORCEPROP 2 LAST CDS_LIB standard
J 0
(-2825 2575);
DISPLAY INVISIBLE (-2825 2575);
FORCEPROP 1 LAST BODY_TYPE PLUMBING
J 2
(-2825 2625);
DISPLAY 0.872340 (-2825 2625);
PAINT GREEN (-2825 2625);
DISPLAY INVISIBLE (-2825 2625);
FORCEPROP 1 LAST HDL_TAP TRUE
J 2
(-3150 2450);
DISPLAY 0.872340 (-3150 2450);
DISPLAY INVISIBLE (-3150 2450);
FORCEPROP 1 LAST PATH I36
J 2
(-2823 2575);
DISPLAY 0.872340 (-2823 2575);
PAINT GREEN (-2823 2575);
DISPLAY INVISIBLE (-2823 2575);
FORCEADD TAP..1
R 2
(-2825 2675);
FORCEPROP 3 LASTPIN (-2775 2675) SIG_NAME M_C_CPU1_SA_CB<5>
J 0
(-2765 2685);
DISPLAY 0.659574 (-2765 2685);
PAINT MONO (-2765 2685);
DISPLAY INVISIBLE (-2765 2685);
FORCEPROP 1 LASTPIN (-2775 2675) BN 5
J 2
(-2763 2683);
DISPLAY 0.680851 (-2763 2683);
PAINT GREEN (-2763 2683);
FORCEPROP 2 LAST CDS_LIB standard
J 0
(-2825 2675);
DISPLAY INVISIBLE (-2825 2675);
FORCEPROP 1 LAST BODY_TYPE PLUMBING
J 2
(-2825 2725);
DISPLAY 0.872340 (-2825 2725);
PAINT GREEN (-2825 2725);
DISPLAY INVISIBLE (-2825 2725);
FORCEPROP 1 LAST HDL_TAP TRUE
J 2
(-3150 2550);
DISPLAY 0.872340 (-3150 2550);
DISPLAY INVISIBLE (-3150 2550);
FORCEPROP 1 LAST PATH I37
J 2
(-2823 2675);
DISPLAY 0.872340 (-2823 2675);
PAINT GREEN (-2823 2675);
DISPLAY INVISIBLE (-2823 2675);
FORCEADD TAP..1
R 2
(-2825 2625);
FORCEPROP 3 LASTPIN (-2775 2625) SIG_NAME M_C_CPU1_SA_CB<4>
J 0
(-2765 2635);
DISPLAY 0.659574 (-2765 2635);
PAINT MONO (-2765 2635);
DISPLAY INVISIBLE (-2765 2635);
FORCEPROP 1 LASTPIN (-2775 2625) BN 4
J 2
(-2763 2633);
DISPLAY 0.680851 (-2763 2633);
PAINT GREEN (-2763 2633);
FORCEPROP 2 LAST CDS_LIB standard
J 0
(-2825 2625);
DISPLAY INVISIBLE (-2825 2625);
FORCEPROP 1 LAST BODY_TYPE PLUMBING
J 2
(-2825 2675);
DISPLAY 0.872340 (-2825 2675);
PAINT GREEN (-2825 2675);
DISPLAY INVISIBLE (-2825 2675);
FORCEPROP 1 LAST HDL_TAP TRUE
J 2
(-3150 2500);
DISPLAY 0.872340 (-3150 2500);
DISPLAY INVISIBLE (-3150 2500);
FORCEPROP 1 LAST PATH I38
J 2
(-2823 2625);
DISPLAY 0.872340 (-2823 2625);
PAINT GREEN (-2823 2625);
DISPLAY INVISIBLE (-2823 2625);
FORCEADD TAP..1
R 2
(-2825 2725);
FORCEPROP 3 LASTPIN (-2775 2725) SIG_NAME M_C_CPU1_SA_CB<6>
J 0
(-2765 2735);
DISPLAY 0.659574 (-2765 2735);
PAINT MONO (-2765 2735);
DISPLAY INVISIBLE (-2765 2735);
FORCEPROP 1 LASTPIN (-2775 2725) BN 6
J 2
(-2763 2733);
DISPLAY 0.680851 (-2763 2733);
PAINT GREEN (-2763 2733);
FORCEPROP 2 LAST CDS_LIB standard
J 0
(-2825 2725);
DISPLAY INVISIBLE (-2825 2725);
FORCEPROP 1 LAST BODY_TYPE PLUMBING
J 2
(-2825 2775);
DISPLAY 0.872340 (-2825 2775);
PAINT GREEN (-2825 2775);
DISPLAY INVISIBLE (-2825 2775);
FORCEPROP 1 LAST HDL_TAP TRUE
J 2
(-3150 2600);
DISPLAY 0.872340 (-3150 2600);
DISPLAY INVISIBLE (-3150 2600);
FORCEPROP 1 LAST PATH I39
J 2
(-2823 2725);
DISPLAY 0.872340 (-2823 2725);
PAINT GREEN (-2823 2725);
DISPLAY INVISIBLE (-2823 2725);
FORCEADD OFFPAGE..2
R 2
(-3750 775);
FORCEPROP 2 LAST $XR0 53 
J 0
(-3974 775);
DISPLAY 0.638298 (-3974 775);
PAINT MONO (-3974 775);
FORCEPROP 2 LAST CDS_LIB standard
J 0
(-3750 775);
PAINT MONO (-3750 775);
DISPLAY INVISIBLE (-3750 775);
FORCEPROP 1 LAST OFFPAGE TRUE
J 2
(-4075 650);
DISPLAY 0.872340 (-4075 650);
DISPLAY INVISIBLE (-4075 650);
FORCEPROP 1 LAST COMMENT_BODY TRUE
J 2
(-3705 680);
DISPLAY 0.872340 (-3705 680);
PAINT GREEN (-3705 680);
DISPLAY INVISIBLE (-3705 680);
FORCEPROP 2 LAST PATH I4
J 0
(-3700 850);
DISPLAY 1.021277 (-3700 850);
DISPLAY INVISIBLE (-3700 850);
FORCEADD TAP..1
R 2
(-2825 2775);
FORCEPROP 3 LASTPIN (-2775 2775) SIG_NAME M_C_CPU1_SA_CB<7>
J 0
(-2765 2785);
DISPLAY 0.659574 (-2765 2785);
PAINT MONO (-2765 2785);
DISPLAY INVISIBLE (-2765 2785);
FORCEPROP 1 LASTPIN (-2775 2775) BN 7
J 2
(-2763 2783);
DISPLAY 0.680851 (-2763 2783);
PAINT GREEN (-2763 2783);
FORCEPROP 2 LAST CDS_LIB standard
J 0
(-2825 2775);
DISPLAY INVISIBLE (-2825 2775);
FORCEPROP 1 LAST BODY_TYPE PLUMBING
J 2
(-2825 2825);
DISPLAY 0.872340 (-2825 2825);
PAINT GREEN (-2825 2825);
DISPLAY INVISIBLE (-2825 2825);
FORCEPROP 1 LAST HDL_TAP TRUE
J 2
(-3150 2650);
DISPLAY 0.872340 (-3150 2650);
DISPLAY INVISIBLE (-3150 2650);
FORCEPROP 1 LAST PATH I40
J 2
(-2823 2775);
DISPLAY 0.872340 (-2823 2775);
PAINT GREEN (-2823 2775);
DISPLAY INVISIBLE (-2823 2775);
FORCEADD TAP..1
R 2
(-2825 3475);
FORCEPROP 3 LASTPIN (-2775 3475) SIG_NAME M_C_CPU1_SB_CA<0>
J 0
(-2765 3485);
DISPLAY 0.659574 (-2765 3485);
PAINT MONO (-2765 3485);
DISPLAY INVISIBLE (-2765 3485);
FORCEPROP 1 LASTPIN (-2775 3475) BN 0
J 2
(-2763 3483);
DISPLAY 0.680851 (-2763 3483);
PAINT GREEN (-2763 3483);
FORCEPROP 2 LAST CDS_LIB standard
J 0
(-2825 3475);
DISPLAY INVISIBLE (-2825 3475);
FORCEPROP 1 LAST BODY_TYPE PLUMBING
J 2
(-2825 3525);
DISPLAY 0.872340 (-2825 3525);
PAINT GREEN (-2825 3525);
DISPLAY INVISIBLE (-2825 3525);
FORCEPROP 1 LAST HDL_TAP TRUE
J 2
(-3150 3350);
DISPLAY 0.872340 (-3150 3350);
DISPLAY INVISIBLE (-3150 3350);
FORCEPROP 1 LAST PATH I41
J 2
(-2823 3475);
DISPLAY 0.872340 (-2823 3475);
PAINT GREEN (-2823 3475);
DISPLAY INVISIBLE (-2823 3475);
FORCEADD TAP..1
R 2
(-2825 3575);
FORCEPROP 3 LASTPIN (-2775 3575) SIG_NAME M_C_CPU1_SB_CA<2>
J 0
(-2765 3585);
DISPLAY 0.659574 (-2765 3585);
PAINT MONO (-2765 3585);
DISPLAY INVISIBLE (-2765 3585);
FORCEPROP 1 LASTPIN (-2775 3575) BN 2
J 2
(-2763 3583);
DISPLAY 0.680851 (-2763 3583);
PAINT GREEN (-2763 3583);
FORCEPROP 2 LAST CDS_LIB standard
J 0
(-2825 3575);
DISPLAY INVISIBLE (-2825 3575);
FORCEPROP 1 LAST BODY_TYPE PLUMBING
J 2
(-2825 3625);
DISPLAY 0.872340 (-2825 3625);
PAINT GREEN (-2825 3625);
DISPLAY INVISIBLE (-2825 3625);
FORCEPROP 1 LAST HDL_TAP TRUE
J 2
(-3150 3450);
DISPLAY 0.872340 (-3150 3450);
DISPLAY INVISIBLE (-3150 3450);
FORCEPROP 1 LAST PATH I42
J 2
(-2823 3575);
DISPLAY 0.872340 (-2823 3575);
PAINT GREEN (-2823 3575);
DISPLAY INVISIBLE (-2823 3575);
FORCEADD TAP..1
R 2
(-2825 3525);
FORCEPROP 3 LASTPIN (-2775 3525) SIG_NAME M_C_CPU1_SB_CA<1>
J 0
(-2765 3535);
DISPLAY 0.659574 (-2765 3535);
PAINT MONO (-2765 3535);
DISPLAY INVISIBLE (-2765 3535);
FORCEPROP 1 LASTPIN (-2775 3525) BN 1
J 2
(-2763 3533);
DISPLAY 0.680851 (-2763 3533);
PAINT GREEN (-2763 3533);
FORCEPROP 2 LAST CDS_LIB standard
J 0
(-2825 3525);
DISPLAY INVISIBLE (-2825 3525);
FORCEPROP 1 LAST BODY_TYPE PLUMBING
J 2
(-2825 3575);
DISPLAY 0.872340 (-2825 3575);
PAINT GREEN (-2825 3575);
DISPLAY INVISIBLE (-2825 3575);
FORCEPROP 1 LAST HDL_TAP TRUE
J 2
(-3150 3400);
DISPLAY 0.872340 (-3150 3400);
DISPLAY INVISIBLE (-3150 3400);
FORCEPROP 1 LAST PATH I43
J 2
(-2823 3525);
DISPLAY 0.872340 (-2823 3525);
PAINT GREEN (-2823 3525);
DISPLAY INVISIBLE (-2823 3525);
FORCEADD TAP..1
R 2
(-2825 3625);
FORCEPROP 3 LASTPIN (-2775 3625) SIG_NAME M_C_CPU1_SB_CA<3>
J 0
(-2765 3635);
DISPLAY 0.659574 (-2765 3635);
PAINT MONO (-2765 3635);
DISPLAY INVISIBLE (-2765 3635);
FORCEPROP 1 LASTPIN (-2775 3625) BN 3
J 2
(-2763 3633);
DISPLAY 0.680851 (-2763 3633);
PAINT GREEN (-2763 3633);
FORCEPROP 2 LAST CDS_LIB standard
J 0
(-2825 3625);
DISPLAY INVISIBLE (-2825 3625);
FORCEPROP 1 LAST BODY_TYPE PLUMBING
J 2
(-2825 3675);
DISPLAY 0.872340 (-2825 3675);
PAINT GREEN (-2825 3675);
DISPLAY INVISIBLE (-2825 3675);
FORCEPROP 1 LAST HDL_TAP TRUE
J 2
(-3150 3500);
DISPLAY 0.872340 (-3150 3500);
DISPLAY INVISIBLE (-3150 3500);
FORCEPROP 1 LAST PATH I44
J 2
(-2823 3625);
DISPLAY 0.872340 (-2823 3625);
PAINT GREEN (-2823 3625);
DISPLAY INVISIBLE (-2823 3625);
FORCEADD TAP..1
R 2
(-2825 3675);
FORCEPROP 3 LASTPIN (-2775 3675) SIG_NAME M_C_CPU1_SB_CA<4>
J 0
(-2765 3685);
DISPLAY 0.659574 (-2765 3685);
PAINT MONO (-2765 3685);
DISPLAY INVISIBLE (-2765 3685);
FORCEPROP 1 LASTPIN (-2775 3675) BN 4
J 2
(-2763 3683);
DISPLAY 0.680851 (-2763 3683);
PAINT GREEN (-2763 3683);
FORCEPROP 2 LAST CDS_LIB standard
J 0
(-2825 3675);
DISPLAY INVISIBLE (-2825 3675);
FORCEPROP 1 LAST BODY_TYPE PLUMBING
J 2
(-2825 3725);
DISPLAY 0.872340 (-2825 3725);
PAINT GREEN (-2825 3725);
DISPLAY INVISIBLE (-2825 3725);
FORCEPROP 1 LAST HDL_TAP TRUE
J 2
(-3150 3550);
DISPLAY 0.872340 (-3150 3550);
DISPLAY INVISIBLE (-3150 3550);
FORCEPROP 1 LAST PATH I45
J 2
(-2823 3675);
DISPLAY 0.872340 (-2823 3675);
PAINT GREEN (-2823 3675);
DISPLAY INVISIBLE (-2823 3675);
FORCEADD TAP..1
R 2
(-2825 3725);
FORCEPROP 3 LASTPIN (-2775 3725) SIG_NAME M_C_CPU1_SB_CA<5>
J 0
(-2765 3735);
DISPLAY 0.659574 (-2765 3735);
PAINT MONO (-2765 3735);
DISPLAY INVISIBLE (-2765 3735);
FORCEPROP 1 LASTPIN (-2775 3725) BN 5
J 2
(-2763 3733);
DISPLAY 0.680851 (-2763 3733);
PAINT GREEN (-2763 3733);
FORCEPROP 2 LAST CDS_LIB standard
J 0
(-2825 3725);
DISPLAY INVISIBLE (-2825 3725);
FORCEPROP 1 LAST BODY_TYPE PLUMBING
J 2
(-2825 3775);
DISPLAY 0.872340 (-2825 3775);
PAINT GREEN (-2825 3775);
DISPLAY INVISIBLE (-2825 3775);
FORCEPROP 1 LAST HDL_TAP TRUE
J 2
(-3150 3600);
DISPLAY 0.872340 (-3150 3600);
DISPLAY INVISIBLE (-3150 3600);
FORCEPROP 1 LAST PATH I46
J 2
(-2823 3725);
DISPLAY 0.872340 (-2823 3725);
PAINT GREEN (-2823 3725);
DISPLAY INVISIBLE (-2823 3725);
FORCEADD TAP..1
R 2
(-2825 3775);
FORCEPROP 3 LASTPIN (-2775 3775) SIG_NAME M_C_CPU1_SB_CA<6>
J 0
(-2765 3785);
DISPLAY 0.659574 (-2765 3785);
PAINT MONO (-2765 3785);
DISPLAY INVISIBLE (-2765 3785);
FORCEPROP 1 LASTPIN (-2775 3775) BN 6
J 2
(-2763 3783);
DISPLAY 0.680851 (-2763 3783);
PAINT GREEN (-2763 3783);
FORCEPROP 2 LAST CDS_LIB standard
J 0
(-2825 3775);
DISPLAY INVISIBLE (-2825 3775);
FORCEPROP 1 LAST BODY_TYPE PLUMBING
J 2
(-2825 3825);
DISPLAY 0.872340 (-2825 3825);
PAINT GREEN (-2825 3825);
DISPLAY INVISIBLE (-2825 3825);
FORCEPROP 1 LAST HDL_TAP TRUE
J 2
(-3150 3650);
DISPLAY 0.872340 (-3150 3650);
DISPLAY INVISIBLE (-3150 3650);
FORCEPROP 1 LAST PATH I47
J 2
(-2823 3775);
DISPLAY 0.872340 (-2823 3775);
PAINT GREEN (-2823 3775);
DISPLAY INVISIBLE (-2823 3775);
FORCEADD TAP..1
R 2
(-2825 3925);
FORCEPROP 3 LASTPIN (-2775 3925) SIG_NAME M_C_CPU1_SA_CA<1>
J 0
(-2765 3935);
DISPLAY 0.659574 (-2765 3935);
PAINT MONO (-2765 3935);
DISPLAY INVISIBLE (-2765 3935);
FORCEPROP 1 LASTPIN (-2775 3925) BN 1
J 2
(-2763 3933);
DISPLAY 0.680851 (-2763 3933);
PAINT GREEN (-2763 3933);
FORCEPROP 2 LAST CDS_LIB standard
J 0
(-2825 3925);
DISPLAY INVISIBLE (-2825 3925);
FORCEPROP 1 LAST BODY_TYPE PLUMBING
J 2
(-2825 3975);
DISPLAY 0.872340 (-2825 3975);
PAINT GREEN (-2825 3975);
DISPLAY INVISIBLE (-2825 3975);
FORCEPROP 1 LAST HDL_TAP TRUE
J 2
(-3150 3800);
DISPLAY 0.872340 (-3150 3800);
DISPLAY INVISIBLE (-3150 3800);
FORCEPROP 1 LAST PATH I48
J 2
(-2823 3925);
DISPLAY 0.872340 (-2823 3925);
PAINT GREEN (-2823 3925);
DISPLAY INVISIBLE (-2823 3925);
FORCEADD TAP..1
R 2
(-2825 3875);
FORCEPROP 3 LASTPIN (-2775 3875) SIG_NAME M_C_CPU1_SA_CA<0>
J 0
(-2765 3885);
DISPLAY 0.659574 (-2765 3885);
PAINT MONO (-2765 3885);
DISPLAY INVISIBLE (-2765 3885);
FORCEPROP 1 LASTPIN (-2775 3875) BN 0
J 2
(-2763 3883);
DISPLAY 0.680851 (-2763 3883);
PAINT GREEN (-2763 3883);
FORCEPROP 2 LAST CDS_LIB standard
J 0
(-2825 3875);
DISPLAY INVISIBLE (-2825 3875);
FORCEPROP 1 LAST BODY_TYPE PLUMBING
J 2
(-2825 3925);
DISPLAY 0.872340 (-2825 3925);
PAINT GREEN (-2825 3925);
DISPLAY INVISIBLE (-2825 3925);
FORCEPROP 1 LAST HDL_TAP TRUE
J 2
(-3150 3750);
DISPLAY 0.872340 (-3150 3750);
DISPLAY INVISIBLE (-3150 3750);
FORCEPROP 1 LAST PATH I49
J 2
(-2823 3875);
DISPLAY 0.872340 (-2823 3875);
PAINT GREEN (-2823 3875);
DISPLAY INVISIBLE (-2823 3875);
FORCEADD OFFPAGE..2
R 2
(-3750 725);
FORCEPROP 2 LAST $XR0 53 
J 0
(-3974 725);
DISPLAY 0.638298 (-3974 725);
PAINT MONO (-3974 725);
FORCEPROP 2 LAST CDS_LIB standard
J 0
(-3750 725);
PAINT MONO (-3750 725);
DISPLAY INVISIBLE (-3750 725);
FORCEPROP 1 LAST OFFPAGE TRUE
J 2
(-4075 600);
DISPLAY 0.872340 (-4075 600);
DISPLAY INVISIBLE (-4075 600);
FORCEPROP 1 LAST COMMENT_BODY TRUE
J 2
(-3705 630);
DISPLAY 0.872340 (-3705 630);
PAINT GREEN (-3705 630);
DISPLAY INVISIBLE (-3705 630);
FORCEPROP 2 LAST PATH I5
J 0
(-3700 800);
DISPLAY 1.021277 (-3700 800);
DISPLAY INVISIBLE (-3700 800);
FORCEADD TAP..1
R 2
(-2825 3975);
FORCEPROP 3 LASTPIN (-2775 3975) SIG_NAME M_C_CPU1_SA_CA<2>
J 0
(-2765 3985);
DISPLAY 0.659574 (-2765 3985);
PAINT MONO (-2765 3985);
DISPLAY INVISIBLE (-2765 3985);
FORCEPROP 1 LASTPIN (-2775 3975) BN 2
J 2
(-2763 3983);
DISPLAY 0.680851 (-2763 3983);
PAINT GREEN (-2763 3983);
FORCEPROP 2 LAST CDS_LIB standard
J 0
(-2825 3975);
DISPLAY INVISIBLE (-2825 3975);
FORCEPROP 1 LAST BODY_TYPE PLUMBING
J 2
(-2825 4025);
DISPLAY 0.872340 (-2825 4025);
PAINT GREEN (-2825 4025);
DISPLAY INVISIBLE (-2825 4025);
FORCEPROP 1 LAST HDL_TAP TRUE
J 2
(-3150 3850);
DISPLAY 0.872340 (-3150 3850);
DISPLAY INVISIBLE (-3150 3850);
FORCEPROP 1 LAST PATH I50
J 2
(-2823 3975);
DISPLAY 0.872340 (-2823 3975);
PAINT GREEN (-2823 3975);
DISPLAY INVISIBLE (-2823 3975);
FORCEADD TAP..1
R 2
(-2825 4075);
FORCEPROP 3 LASTPIN (-2775 4075) SIG_NAME M_C_CPU1_SA_CA<4>
J 0
(-2765 4085);
DISPLAY 0.659574 (-2765 4085);
PAINT MONO (-2765 4085);
DISPLAY INVISIBLE (-2765 4085);
FORCEPROP 1 LASTPIN (-2775 4075) BN 4
J 2
(-2763 4083);
DISPLAY 0.680851 (-2763 4083);
PAINT GREEN (-2763 4083);
FORCEPROP 2 LAST CDS_LIB standard
J 0
(-2825 4075);
DISPLAY INVISIBLE (-2825 4075);
FORCEPROP 1 LAST BODY_TYPE PLUMBING
J 2
(-2825 4125);
DISPLAY 0.872340 (-2825 4125);
PAINT GREEN (-2825 4125);
DISPLAY INVISIBLE (-2825 4125);
FORCEPROP 1 LAST HDL_TAP TRUE
J 2
(-3150 3950);
DISPLAY 0.872340 (-3150 3950);
DISPLAY INVISIBLE (-3150 3950);
FORCEPROP 1 LAST PATH I51
J 2
(-2823 4075);
DISPLAY 0.872340 (-2823 4075);
PAINT GREEN (-2823 4075);
DISPLAY INVISIBLE (-2823 4075);
FORCEADD TAP..1
R 2
(-2825 4025);
FORCEPROP 3 LASTPIN (-2775 4025) SIG_NAME M_C_CPU1_SA_CA<3>
J 0
(-2765 4035);
DISPLAY 0.659574 (-2765 4035);
PAINT MONO (-2765 4035);
DISPLAY INVISIBLE (-2765 4035);
FORCEPROP 1 LASTPIN (-2775 4025) BN 3
J 2
(-2763 4033);
DISPLAY 0.680851 (-2763 4033);
PAINT GREEN (-2763 4033);
FORCEPROP 2 LAST CDS_LIB standard
J 0
(-2825 4025);
DISPLAY INVISIBLE (-2825 4025);
FORCEPROP 1 LAST BODY_TYPE PLUMBING
J 2
(-2825 4075);
DISPLAY 0.872340 (-2825 4075);
PAINT GREEN (-2825 4075);
DISPLAY INVISIBLE (-2825 4075);
FORCEPROP 1 LAST HDL_TAP TRUE
J 2
(-3150 3900);
DISPLAY 0.872340 (-3150 3900);
DISPLAY INVISIBLE (-3150 3900);
FORCEPROP 1 LAST PATH I52
J 2
(-2823 4025);
DISPLAY 0.872340 (-2823 4025);
PAINT GREEN (-2823 4025);
DISPLAY INVISIBLE (-2823 4025);
FORCEADD TAP..1
(-1175 1025);
FORCEPROP 3 LASTPIN (-1225 1025) SIG_NAME M_C_CPU1_SB_DQ<1>
J 0
(-1215 1035);
DISPLAY 0.659574 (-1215 1035);
PAINT MONO (-1215 1035);
DISPLAY INVISIBLE (-1215 1035);
FORCEPROP 1 LASTPIN (-1225 1025) BN 1
J 0
(-1237 1033);
DISPLAY 0.680851 (-1237 1033);
PAINT GREEN (-1237 1033);
FORCEPROP 2 LAST CDS_LIB standard
J 0
(-1175 1025);
PAINT MONO (-1175 1025);
DISPLAY INVISIBLE (-1175 1025);
FORCEPROP 1 LAST BODY_TYPE PLUMBING
J 0
(-1175 1075);
DISPLAY 0.872340 (-1175 1075);
PAINT GREEN (-1175 1075);
DISPLAY INVISIBLE (-1175 1075);
FORCEPROP 1 LAST HDL_TAP TRUE
J 0
(-850 900);
DISPLAY 0.872340 (-850 900);
DISPLAY INVISIBLE (-850 900);
FORCEPROP 1 LAST PATH I53
J 0
(-1177 1025);
DISPLAY 0.872340 (-1177 1025);
PAINT GREEN (-1177 1025);
DISPLAY INVISIBLE (-1177 1025);
FORCEADD TAP..1
(-1175 975);
FORCEPROP 3 LASTPIN (-1225 975) SIG_NAME M_C_CPU1_SB_DQ<0>
J 0
(-1215 985);
DISPLAY 0.659574 (-1215 985);
PAINT MONO (-1215 985);
DISPLAY INVISIBLE (-1215 985);
FORCEPROP 1 LASTPIN (-1225 975) BN 0
J 0
(-1237 983);
DISPLAY 0.680851 (-1237 983);
PAINT GREEN (-1237 983);
FORCEPROP 2 LAST CDS_LIB standard
J 0
(-1175 975);
PAINT MONO (-1175 975);
DISPLAY INVISIBLE (-1175 975);
FORCEPROP 1 LAST BODY_TYPE PLUMBING
J 0
(-1175 1025);
DISPLAY 0.872340 (-1175 1025);
PAINT GREEN (-1175 1025);
DISPLAY INVISIBLE (-1175 1025);
FORCEPROP 1 LAST HDL_TAP TRUE
J 0
(-850 850);
DISPLAY 0.872340 (-850 850);
DISPLAY INVISIBLE (-850 850);
FORCEPROP 1 LAST PATH I54
J 0
(-1177 975);
DISPLAY 0.872340 (-1177 975);
PAINT GREEN (-1177 975);
DISPLAY INVISIBLE (-1177 975);
FORCEADD TAP..1
(-1175 1075);
FORCEPROP 3 LASTPIN (-1225 1075) SIG_NAME M_C_CPU1_SB_DQ<2>
J 0
(-1215 1085);
DISPLAY 0.659574 (-1215 1085);
PAINT MONO (-1215 1085);
DISPLAY INVISIBLE (-1215 1085);
FORCEPROP 1 LASTPIN (-1225 1075) BN 2
J 0
(-1237 1083);
DISPLAY 0.680851 (-1237 1083);
PAINT GREEN (-1237 1083);
FORCEPROP 2 LAST CDS_LIB standard
J 0
(-1175 1075);
PAINT MONO (-1175 1075);
DISPLAY INVISIBLE (-1175 1075);
FORCEPROP 1 LAST BODY_TYPE PLUMBING
J 0
(-1175 1125);
DISPLAY 0.872340 (-1175 1125);
PAINT GREEN (-1175 1125);
DISPLAY INVISIBLE (-1175 1125);
FORCEPROP 1 LAST HDL_TAP TRUE
J 0
(-850 950);
DISPLAY 0.872340 (-850 950);
DISPLAY INVISIBLE (-850 950);
FORCEPROP 1 LAST PATH I55
J 0
(-1177 1075);
DISPLAY 0.872340 (-1177 1075);
PAINT GREEN (-1177 1075);
DISPLAY INVISIBLE (-1177 1075);
FORCEADD TAP..1
(-1175 1175);
FORCEPROP 3 LASTPIN (-1225 1175) SIG_NAME M_C_CPU1_SB_DQ<4>
J 0
(-1215 1185);
DISPLAY 0.659574 (-1215 1185);
PAINT MONO (-1215 1185);
DISPLAY INVISIBLE (-1215 1185);
FORCEPROP 1 LASTPIN (-1225 1175) BN 4
J 0
(-1237 1183);
DISPLAY 0.680851 (-1237 1183);
PAINT GREEN (-1237 1183);
FORCEPROP 2 LAST CDS_LIB standard
J 0
(-1175 1175);
PAINT MONO (-1175 1175);
DISPLAY INVISIBLE (-1175 1175);
FORCEPROP 1 LAST BODY_TYPE PLUMBING
J 0
(-1175 1225);
DISPLAY 0.872340 (-1175 1225);
PAINT GREEN (-1175 1225);
DISPLAY INVISIBLE (-1175 1225);
FORCEPROP 1 LAST HDL_TAP TRUE
J 0
(-850 1050);
DISPLAY 0.872340 (-850 1050);
DISPLAY INVISIBLE (-850 1050);
FORCEPROP 1 LAST PATH I56
J 0
(-1177 1175);
DISPLAY 0.872340 (-1177 1175);
PAINT GREEN (-1177 1175);
DISPLAY INVISIBLE (-1177 1175);
FORCEADD TAP..1
(-1175 1125);
FORCEPROP 3 LASTPIN (-1225 1125) SIG_NAME M_C_CPU1_SB_DQ<3>
J 0
(-1215 1135);
DISPLAY 0.659574 (-1215 1135);
PAINT MONO (-1215 1135);
DISPLAY INVISIBLE (-1215 1135);
FORCEPROP 1 LASTPIN (-1225 1125) BN 3
J 0
(-1237 1133);
DISPLAY 0.680851 (-1237 1133);
PAINT GREEN (-1237 1133);
FORCEPROP 2 LAST CDS_LIB standard
J 0
(-1175 1125);
PAINT MONO (-1175 1125);
DISPLAY INVISIBLE (-1175 1125);
FORCEPROP 1 LAST BODY_TYPE PLUMBING
J 0
(-1175 1175);
DISPLAY 0.872340 (-1175 1175);
PAINT GREEN (-1175 1175);
DISPLAY INVISIBLE (-1175 1175);
FORCEPROP 1 LAST HDL_TAP TRUE
J 0
(-850 1000);
DISPLAY 0.872340 (-850 1000);
DISPLAY INVISIBLE (-850 1000);
FORCEPROP 1 LAST PATH I57
J 0
(-1177 1125);
DISPLAY 0.872340 (-1177 1125);
PAINT GREEN (-1177 1125);
DISPLAY INVISIBLE (-1177 1125);
FORCEADD TAP..1
(-1175 1225);
FORCEPROP 3 LASTPIN (-1225 1225) SIG_NAME M_C_CPU1_SB_DQ<5>
J 0
(-1215 1235);
DISPLAY 0.659574 (-1215 1235);
PAINT MONO (-1215 1235);
DISPLAY INVISIBLE (-1215 1235);
FORCEPROP 1 LASTPIN (-1225 1225) BN 5
J 0
(-1237 1233);
DISPLAY 0.680851 (-1237 1233);
PAINT GREEN (-1237 1233);
FORCEPROP 2 LAST CDS_LIB standard
J 0
(-1175 1225);
PAINT MONO (-1175 1225);
DISPLAY INVISIBLE (-1175 1225);
FORCEPROP 1 LAST BODY_TYPE PLUMBING
J 0
(-1175 1275);
DISPLAY 0.872340 (-1175 1275);
PAINT GREEN (-1175 1275);
DISPLAY INVISIBLE (-1175 1275);
FORCEPROP 1 LAST HDL_TAP TRUE
J 0
(-850 1100);
DISPLAY 0.872340 (-850 1100);
DISPLAY INVISIBLE (-850 1100);
FORCEPROP 1 LAST PATH I58
J 0
(-1177 1225);
DISPLAY 0.872340 (-1177 1225);
PAINT GREEN (-1177 1225);
DISPLAY INVISIBLE (-1177 1225);
FORCEADD TAP..1
(-1175 1275);
FORCEPROP 3 LASTPIN (-1225 1275) SIG_NAME M_C_CPU1_SB_DQ<6>
J 0
(-1215 1285);
DISPLAY 0.659574 (-1215 1285);
PAINT MONO (-1215 1285);
DISPLAY INVISIBLE (-1215 1285);
FORCEPROP 1 LASTPIN (-1225 1275) BN 6
J 0
(-1237 1283);
DISPLAY 0.680851 (-1237 1283);
PAINT GREEN (-1237 1283);
FORCEPROP 2 LAST CDS_LIB standard
J 0
(-1175 1275);
PAINT MONO (-1175 1275);
DISPLAY INVISIBLE (-1175 1275);
FORCEPROP 1 LAST BODY_TYPE PLUMBING
J 0
(-1175 1325);
DISPLAY 0.872340 (-1175 1325);
PAINT GREEN (-1175 1325);
DISPLAY INVISIBLE (-1175 1325);
FORCEPROP 1 LAST HDL_TAP TRUE
J 0
(-850 1150);
DISPLAY 0.872340 (-850 1150);
DISPLAY INVISIBLE (-850 1150);
FORCEPROP 1 LAST PATH I59
J 0
(-1177 1275);
DISPLAY 0.872340 (-1177 1275);
PAINT GREEN (-1177 1275);
DISPLAY INVISIBLE (-1177 1275);
FORCEADD OFFPAGE..3
R 2
(-3750 1325);
FORCEPROP 2 LAST $XR0 114 
J 0
(-4030 1325);
DISPLAY 0.638298 (-4030 1325);
PAINT MONO (-4030 1325);
FORCEPROP 2 LAST CDS_LIB standard
J 0
(-3750 1325);
PAINT MONO (-3750 1325);
DISPLAY INVISIBLE (-3750 1325);
FORCEPROP 1 LAST OFFPAGE TRUE
J 2
(-4075 1200);
DISPLAY 0.872340 (-4075 1200);
DISPLAY INVISIBLE (-4075 1200);
FORCEPROP 1 LAST COMMENT_BODY TRUE
J 2
(-3700 1225);
DISPLAY 0.872340 (-3700 1225);
PAINT GREEN (-3700 1225);
DISPLAY INVISIBLE (-3700 1225);
FORCEPROP 2 LAST PATH I6
J 0
(-3700 1400);
DISPLAY 1.021277 (-3700 1400);
DISPLAY INVISIBLE (-3700 1400);
FORCEADD TAP..1
(-1175 1325);
FORCEPROP 3 LASTPIN (-1225 1325) SIG_NAME M_C_CPU1_SB_DQ<7>
J 0
(-1215 1335);
DISPLAY 0.659574 (-1215 1335);
PAINT MONO (-1215 1335);
DISPLAY INVISIBLE (-1215 1335);
FORCEPROP 1 LASTPIN (-1225 1325) BN 7
J 0
(-1237 1333);
DISPLAY 0.680851 (-1237 1333);
PAINT GREEN (-1237 1333);
FORCEPROP 2 LAST CDS_LIB standard
J 0
(-1175 1325);
PAINT MONO (-1175 1325);
DISPLAY INVISIBLE (-1175 1325);
FORCEPROP 1 LAST BODY_TYPE PLUMBING
J 0
(-1175 1375);
DISPLAY 0.872340 (-1175 1375);
PAINT GREEN (-1175 1375);
DISPLAY INVISIBLE (-1175 1375);
FORCEPROP 1 LAST HDL_TAP TRUE
J 0
(-850 1200);
DISPLAY 0.872340 (-850 1200);
DISPLAY INVISIBLE (-850 1200);
FORCEPROP 1 LAST PATH I60
J 0
(-1177 1325);
DISPLAY 0.872340 (-1177 1325);
PAINT GREEN (-1177 1325);
DISPLAY INVISIBLE (-1177 1325);
FORCEADD TAP..1
(-1175 1375);
FORCEPROP 3 LASTPIN (-1225 1375) SIG_NAME M_C_CPU1_SB_DQ<8>
J 0
(-1215 1385);
DISPLAY 0.659574 (-1215 1385);
PAINT MONO (-1215 1385);
DISPLAY INVISIBLE (-1215 1385);
FORCEPROP 1 LASTPIN (-1225 1375) BN 8
J 0
(-1237 1383);
DISPLAY 0.680851 (-1237 1383);
PAINT GREEN (-1237 1383);
FORCEPROP 2 LAST CDS_LIB standard
J 0
(-1175 1375);
PAINT MONO (-1175 1375);
DISPLAY INVISIBLE (-1175 1375);
FORCEPROP 1 LAST BODY_TYPE PLUMBING
J 0
(-1175 1425);
DISPLAY 0.872340 (-1175 1425);
PAINT GREEN (-1175 1425);
DISPLAY INVISIBLE (-1175 1425);
FORCEPROP 1 LAST HDL_TAP TRUE
J 0
(-850 1250);
DISPLAY 0.872340 (-850 1250);
DISPLAY INVISIBLE (-850 1250);
FORCEPROP 1 LAST PATH I61
J 0
(-1177 1375);
DISPLAY 0.872340 (-1177 1375);
PAINT GREEN (-1177 1375);
DISPLAY INVISIBLE (-1177 1375);
FORCEADD TAP..1
(-1175 1425);
FORCEPROP 3 LASTPIN (-1225 1425) SIG_NAME M_C_CPU1_SB_DQ<9>
J 0
(-1215 1435);
DISPLAY 0.659574 (-1215 1435);
PAINT MONO (-1215 1435);
DISPLAY INVISIBLE (-1215 1435);
FORCEPROP 1 LASTPIN (-1225 1425) BN 9
J 0
(-1237 1433);
DISPLAY 0.680851 (-1237 1433);
PAINT GREEN (-1237 1433);
FORCEPROP 2 LAST CDS_LIB standard
J 0
(-1175 1425);
PAINT MONO (-1175 1425);
DISPLAY INVISIBLE (-1175 1425);
FORCEPROP 1 LAST BODY_TYPE PLUMBING
J 0
(-1175 1475);
DISPLAY 0.872340 (-1175 1475);
PAINT GREEN (-1175 1475);
DISPLAY INVISIBLE (-1175 1475);
FORCEPROP 1 LAST HDL_TAP TRUE
J 0
(-850 1300);
DISPLAY 0.872340 (-850 1300);
DISPLAY INVISIBLE (-850 1300);
FORCEPROP 1 LAST PATH I62
J 0
(-1177 1425);
DISPLAY 0.872340 (-1177 1425);
PAINT GREEN (-1177 1425);
DISPLAY INVISIBLE (-1177 1425);
FORCEADD TAP..1
(-1175 1525);
FORCEPROP 3 LASTPIN (-1225 1525) SIG_NAME M_C_CPU1_SB_DQ<11>
J 0
(-1215 1535);
DISPLAY 0.659574 (-1215 1535);
PAINT MONO (-1215 1535);
DISPLAY INVISIBLE (-1215 1535);
FORCEPROP 1 LASTPIN (-1225 1525) BN 11
J 0
(-1237 1533);
DISPLAY 0.680851 (-1237 1533);
PAINT GREEN (-1237 1533);
FORCEPROP 2 LAST CDS_LIB standard
J 0
(-1175 1525);
PAINT MONO (-1175 1525);
DISPLAY INVISIBLE (-1175 1525);
FORCEPROP 1 LAST BODY_TYPE PLUMBING
J 0
(-1175 1575);
DISPLAY 0.872340 (-1175 1575);
PAINT GREEN (-1175 1575);
DISPLAY INVISIBLE (-1175 1575);
FORCEPROP 1 LAST HDL_TAP TRUE
J 0
(-850 1400);
DISPLAY 0.872340 (-850 1400);
DISPLAY INVISIBLE (-850 1400);
FORCEPROP 1 LAST PATH I63
J 0
(-1177 1525);
DISPLAY 0.872340 (-1177 1525);
PAINT GREEN (-1177 1525);
DISPLAY INVISIBLE (-1177 1525);
FORCEADD TAP..1
(-1175 1475);
FORCEPROP 3 LASTPIN (-1225 1475) SIG_NAME M_C_CPU1_SB_DQ<10>
J 0
(-1215 1485);
DISPLAY 0.659574 (-1215 1485);
PAINT MONO (-1215 1485);
DISPLAY INVISIBLE (-1215 1485);
FORCEPROP 1 LASTPIN (-1225 1475) BN 10
J 0
(-1237 1483);
DISPLAY 0.680851 (-1237 1483);
PAINT GREEN (-1237 1483);
FORCEPROP 2 LAST CDS_LIB standard
J 0
(-1175 1475);
PAINT MONO (-1175 1475);
DISPLAY INVISIBLE (-1175 1475);
FORCEPROP 1 LAST BODY_TYPE PLUMBING
J 0
(-1175 1525);
DISPLAY 0.872340 (-1175 1525);
PAINT GREEN (-1175 1525);
DISPLAY INVISIBLE (-1175 1525);
FORCEPROP 1 LAST HDL_TAP TRUE
J 0
(-850 1350);
DISPLAY 0.872340 (-850 1350);
DISPLAY INVISIBLE (-850 1350);
FORCEPROP 1 LAST PATH I64
J 0
(-1177 1475);
DISPLAY 0.872340 (-1177 1475);
PAINT GREEN (-1177 1475);
DISPLAY INVISIBLE (-1177 1475);
FORCEADD TAP..1
(-1175 1575);
FORCEPROP 3 LASTPIN (-1225 1575) SIG_NAME M_C_CPU1_SB_DQ<12>
J 0
(-1215 1585);
DISPLAY 0.659574 (-1215 1585);
PAINT MONO (-1215 1585);
DISPLAY INVISIBLE (-1215 1585);
FORCEPROP 1 LASTPIN (-1225 1575) BN 12
J 0
(-1237 1583);
DISPLAY 0.680851 (-1237 1583);
PAINT GREEN (-1237 1583);
FORCEPROP 2 LAST CDS_LIB standard
J 0
(-1175 1575);
PAINT MONO (-1175 1575);
DISPLAY INVISIBLE (-1175 1575);
FORCEPROP 1 LAST BODY_TYPE PLUMBING
J 0
(-1175 1625);
DISPLAY 0.872340 (-1175 1625);
PAINT GREEN (-1175 1625);
DISPLAY INVISIBLE (-1175 1625);
FORCEPROP 1 LAST HDL_TAP TRUE
J 0
(-850 1450);
DISPLAY 0.872340 (-850 1450);
DISPLAY INVISIBLE (-850 1450);
FORCEPROP 1 LAST PATH I65
J 0
(-1177 1575);
DISPLAY 0.872340 (-1177 1575);
PAINT GREEN (-1177 1575);
DISPLAY INVISIBLE (-1177 1575);
FORCEADD TAP..1
(-1175 1625);
FORCEPROP 3 LASTPIN (-1225 1625) SIG_NAME M_C_CPU1_SB_DQ<13>
J 0
(-1215 1635);
DISPLAY 0.659574 (-1215 1635);
PAINT MONO (-1215 1635);
DISPLAY INVISIBLE (-1215 1635);
FORCEPROP 1 LASTPIN (-1225 1625) BN 13
J 0
(-1237 1633);
DISPLAY 0.680851 (-1237 1633);
PAINT GREEN (-1237 1633);
FORCEPROP 2 LAST CDS_LIB standard
J 0
(-1175 1625);
PAINT MONO (-1175 1625);
DISPLAY INVISIBLE (-1175 1625);
FORCEPROP 1 LAST BODY_TYPE PLUMBING
J 0
(-1175 1675);
DISPLAY 0.872340 (-1175 1675);
PAINT GREEN (-1175 1675);
DISPLAY INVISIBLE (-1175 1675);
FORCEPROP 1 LAST HDL_TAP TRUE
J 0
(-850 1500);
DISPLAY 0.872340 (-850 1500);
DISPLAY INVISIBLE (-850 1500);
FORCEPROP 1 LAST PATH I66
J 0
(-1177 1625);
DISPLAY 0.872340 (-1177 1625);
PAINT GREEN (-1177 1625);
DISPLAY INVISIBLE (-1177 1625);
FORCEADD TAP..1
(-1175 1675);
FORCEPROP 3 LASTPIN (-1225 1675) SIG_NAME M_C_CPU1_SB_DQ<14>
J 0
(-1215 1685);
DISPLAY 0.659574 (-1215 1685);
PAINT MONO (-1215 1685);
DISPLAY INVISIBLE (-1215 1685);
FORCEPROP 1 LASTPIN (-1225 1675) BN 14
J 0
(-1237 1683);
DISPLAY 0.680851 (-1237 1683);
PAINT GREEN (-1237 1683);
FORCEPROP 2 LAST CDS_LIB standard
J 0
(-1175 1675);
PAINT MONO (-1175 1675);
DISPLAY INVISIBLE (-1175 1675);
FORCEPROP 1 LAST BODY_TYPE PLUMBING
J 0
(-1175 1725);
DISPLAY 0.872340 (-1175 1725);
PAINT GREEN (-1175 1725);
DISPLAY INVISIBLE (-1175 1725);
FORCEPROP 1 LAST HDL_TAP TRUE
J 0
(-850 1550);
DISPLAY 0.872340 (-850 1550);
DISPLAY INVISIBLE (-850 1550);
FORCEPROP 1 LAST PATH I67
J 0
(-1177 1675);
DISPLAY 0.872340 (-1177 1675);
PAINT GREEN (-1177 1675);
DISPLAY INVISIBLE (-1177 1675);
FORCEADD TAP..1
(-1175 1725);
FORCEPROP 3 LASTPIN (-1225 1725) SIG_NAME M_C_CPU1_SB_DQ<15>
J 0
(-1215 1735);
DISPLAY 0.659574 (-1215 1735);
PAINT MONO (-1215 1735);
DISPLAY INVISIBLE (-1215 1735);
FORCEPROP 1 LASTPIN (-1225 1725) BN 15
J 0
(-1237 1733);
DISPLAY 0.680851 (-1237 1733);
PAINT GREEN (-1237 1733);
FORCEPROP 2 LAST CDS_LIB standard
J 0
(-1175 1725);
PAINT MONO (-1175 1725);
DISPLAY INVISIBLE (-1175 1725);
FORCEPROP 1 LAST BODY_TYPE PLUMBING
J 0
(-1175 1775);
DISPLAY 0.872340 (-1175 1775);
PAINT GREEN (-1175 1775);
DISPLAY INVISIBLE (-1175 1775);
FORCEPROP 1 LAST HDL_TAP TRUE
J 0
(-850 1600);
DISPLAY 0.872340 (-850 1600);
DISPLAY INVISIBLE (-850 1600);
FORCEPROP 1 LAST PATH I68
J 0
(-1177 1725);
DISPLAY 0.872340 (-1177 1725);
PAINT GREEN (-1177 1725);
DISPLAY INVISIBLE (-1177 1725);
FORCEADD TAP..1
(-1175 1775);
FORCEPROP 3 LASTPIN (-1225 1775) SIG_NAME M_C_CPU1_SB_DQ<16>
J 0
(-1215 1785);
DISPLAY 0.659574 (-1215 1785);
PAINT MONO (-1215 1785);
DISPLAY INVISIBLE (-1215 1785);
FORCEPROP 1 LASTPIN (-1225 1775) BN 16
J 0
(-1237 1783);
DISPLAY 0.680851 (-1237 1783);
PAINT GREEN (-1237 1783);
FORCEPROP 2 LAST CDS_LIB standard
J 0
(-1175 1775);
PAINT MONO (-1175 1775);
DISPLAY INVISIBLE (-1175 1775);
FORCEPROP 1 LAST BODY_TYPE PLUMBING
J 0
(-1175 1825);
DISPLAY 0.872340 (-1175 1825);
PAINT GREEN (-1175 1825);
DISPLAY INVISIBLE (-1175 1825);
FORCEPROP 1 LAST HDL_TAP TRUE
J 0
(-850 1650);
DISPLAY 0.872340 (-850 1650);
DISPLAY INVISIBLE (-850 1650);
FORCEPROP 1 LAST PATH I69
J 0
(-1177 1775);
DISPLAY 0.872340 (-1177 1775);
PAINT GREEN (-1177 1775);
DISPLAY INVISIBLE (-1177 1775);
FORCEADD TAP..1
(-1175 1825);
FORCEPROP 3 LASTPIN (-1225 1825) SIG_NAME M_C_CPU1_SB_DQ<17>
J 0
(-1215 1835);
DISPLAY 0.659574 (-1215 1835);
PAINT MONO (-1215 1835);
DISPLAY INVISIBLE (-1215 1835);
FORCEPROP 1 LASTPIN (-1225 1825) BN 17
J 0
(-1237 1833);
DISPLAY 0.680851 (-1237 1833);
PAINT GREEN (-1237 1833);
FORCEPROP 2 LAST CDS_LIB standard
J 0
(-1175 1825);
PAINT MONO (-1175 1825);
DISPLAY INVISIBLE (-1175 1825);
FORCEPROP 1 LAST BODY_TYPE PLUMBING
J 0
(-1175 1875);
DISPLAY 0.872340 (-1175 1875);
PAINT GREEN (-1175 1875);
DISPLAY INVISIBLE (-1175 1875);
FORCEPROP 1 LAST HDL_TAP TRUE
J 0
(-850 1700);
DISPLAY 0.872340 (-850 1700);
DISPLAY INVISIBLE (-850 1700);
FORCEPROP 1 LAST PATH I70
J 0
(-1177 1825);
DISPLAY 0.872340 (-1177 1825);
PAINT GREEN (-1177 1825);
DISPLAY INVISIBLE (-1177 1825);
FORCEADD TAP..1
(-1175 1875);
FORCEPROP 3 LASTPIN (-1225 1875) SIG_NAME M_C_CPU1_SB_DQ<18>
J 0
(-1215 1885);
DISPLAY 0.659574 (-1215 1885);
PAINT MONO (-1215 1885);
DISPLAY INVISIBLE (-1215 1885);
FORCEPROP 1 LASTPIN (-1225 1875) BN 18
J 0
(-1237 1883);
DISPLAY 0.680851 (-1237 1883);
PAINT GREEN (-1237 1883);
FORCEPROP 2 LAST CDS_LIB standard
J 0
(-1175 1875);
PAINT MONO (-1175 1875);
DISPLAY INVISIBLE (-1175 1875);
FORCEPROP 1 LAST BODY_TYPE PLUMBING
J 0
(-1175 1925);
DISPLAY 0.872340 (-1175 1925);
PAINT GREEN (-1175 1925);
DISPLAY INVISIBLE (-1175 1925);
FORCEPROP 1 LAST HDL_TAP TRUE
J 0
(-850 1750);
DISPLAY 0.872340 (-850 1750);
DISPLAY INVISIBLE (-850 1750);
FORCEPROP 1 LAST PATH I71
J 0
(-1177 1875);
DISPLAY 0.872340 (-1177 1875);
PAINT GREEN (-1177 1875);
DISPLAY INVISIBLE (-1177 1875);
FORCEADD TAP..1
(-1175 1925);
FORCEPROP 3 LASTPIN (-1225 1925) SIG_NAME M_C_CPU1_SB_DQ<19>
J 0
(-1215 1935);
DISPLAY 0.659574 (-1215 1935);
PAINT MONO (-1215 1935);
DISPLAY INVISIBLE (-1215 1935);
FORCEPROP 1 LASTPIN (-1225 1925) BN 19
J 0
(-1237 1933);
DISPLAY 0.680851 (-1237 1933);
PAINT GREEN (-1237 1933);
FORCEPROP 2 LAST CDS_LIB standard
J 0
(-1175 1925);
PAINT MONO (-1175 1925);
DISPLAY INVISIBLE (-1175 1925);
FORCEPROP 1 LAST BODY_TYPE PLUMBING
J 0
(-1175 1975);
DISPLAY 0.872340 (-1175 1975);
PAINT GREEN (-1175 1975);
DISPLAY INVISIBLE (-1175 1975);
FORCEPROP 1 LAST HDL_TAP TRUE
J 0
(-850 1800);
DISPLAY 0.872340 (-850 1800);
DISPLAY INVISIBLE (-850 1800);
FORCEPROP 1 LAST PATH I72
J 0
(-1177 1925);
DISPLAY 0.872340 (-1177 1925);
PAINT GREEN (-1177 1925);
DISPLAY INVISIBLE (-1177 1925);
FORCEADD TAP..1
(-1175 2025);
FORCEPROP 3 LASTPIN (-1225 2025) SIG_NAME M_C_CPU1_SB_DQ<21>
J 0
(-1215 2035);
DISPLAY 0.659574 (-1215 2035);
PAINT MONO (-1215 2035);
DISPLAY INVISIBLE (-1215 2035);
FORCEPROP 1 LASTPIN (-1225 2025) BN 21
J 0
(-1237 2033);
DISPLAY 0.680851 (-1237 2033);
PAINT GREEN (-1237 2033);
FORCEPROP 2 LAST CDS_LIB standard
J 0
(-1175 2025);
PAINT MONO (-1175 2025);
DISPLAY INVISIBLE (-1175 2025);
FORCEPROP 1 LAST BODY_TYPE PLUMBING
J 0
(-1175 2075);
DISPLAY 0.872340 (-1175 2075);
PAINT GREEN (-1175 2075);
DISPLAY INVISIBLE (-1175 2075);
FORCEPROP 1 LAST HDL_TAP TRUE
J 0
(-850 1900);
DISPLAY 0.872340 (-850 1900);
DISPLAY INVISIBLE (-850 1900);
FORCEPROP 1 LAST PATH I73
J 0
(-1177 2025);
DISPLAY 0.872340 (-1177 2025);
PAINT GREEN (-1177 2025);
DISPLAY INVISIBLE (-1177 2025);
FORCEADD TAP..1
(-1175 1975);
FORCEPROP 3 LASTPIN (-1225 1975) SIG_NAME M_C_CPU1_SB_DQ<20>
J 0
(-1215 1985);
DISPLAY 0.659574 (-1215 1985);
PAINT MONO (-1215 1985);
DISPLAY INVISIBLE (-1215 1985);
FORCEPROP 1 LASTPIN (-1225 1975) BN 20
J 0
(-1237 1983);
DISPLAY 0.680851 (-1237 1983);
PAINT GREEN (-1237 1983);
FORCEPROP 2 LAST CDS_LIB standard
J 0
(-1175 1975);
PAINT MONO (-1175 1975);
DISPLAY INVISIBLE (-1175 1975);
FORCEPROP 1 LAST BODY_TYPE PLUMBING
J 0
(-1175 2025);
DISPLAY 0.872340 (-1175 2025);
PAINT GREEN (-1175 2025);
DISPLAY INVISIBLE (-1175 2025);
FORCEPROP 1 LAST HDL_TAP TRUE
J 0
(-850 1850);
DISPLAY 0.872340 (-850 1850);
DISPLAY INVISIBLE (-850 1850);
FORCEPROP 1 LAST PATH I74
J 0
(-1177 1975);
DISPLAY 0.872340 (-1177 1975);
PAINT GREEN (-1177 1975);
DISPLAY INVISIBLE (-1177 1975);
FORCEADD TAP..1
(-1175 2075);
FORCEPROP 3 LASTPIN (-1225 2075) SIG_NAME M_C_CPU1_SB_DQ<22>
J 0
(-1215 2085);
DISPLAY 0.659574 (-1215 2085);
PAINT MONO (-1215 2085);
DISPLAY INVISIBLE (-1215 2085);
FORCEPROP 1 LASTPIN (-1225 2075) BN 22
J 0
(-1237 2083);
DISPLAY 0.680851 (-1237 2083);
PAINT GREEN (-1237 2083);
FORCEPROP 2 LAST CDS_LIB standard
J 0
(-1175 2075);
DISPLAY INVISIBLE (-1175 2075);
FORCEPROP 1 LAST BODY_TYPE PLUMBING
J 0
(-1175 2125);
DISPLAY 0.872340 (-1175 2125);
PAINT GREEN (-1175 2125);
DISPLAY INVISIBLE (-1175 2125);
FORCEPROP 1 LAST HDL_TAP TRUE
J 0
(-850 1950);
DISPLAY 0.872340 (-850 1950);
DISPLAY INVISIBLE (-850 1950);
FORCEPROP 1 LAST PATH I75
J 0
(-1177 2075);
DISPLAY 0.872340 (-1177 2075);
PAINT GREEN (-1177 2075);
DISPLAY INVISIBLE (-1177 2075);
FORCEADD TAP..1
(-1175 2125);
FORCEPROP 3 LASTPIN (-1225 2125) SIG_NAME M_C_CPU1_SB_DQ<23>
J 0
(-1215 2135);
DISPLAY 0.659574 (-1215 2135);
PAINT MONO (-1215 2135);
DISPLAY INVISIBLE (-1215 2135);
FORCEPROP 1 LASTPIN (-1225 2125) BN 23
J 0
(-1237 2133);
DISPLAY 0.680851 (-1237 2133);
PAINT GREEN (-1237 2133);
FORCEPROP 2 LAST CDS_LIB standard
J 0
(-1175 2125);
DISPLAY INVISIBLE (-1175 2125);
FORCEPROP 1 LAST BODY_TYPE PLUMBING
J 0
(-1175 2175);
DISPLAY 0.872340 (-1175 2175);
PAINT GREEN (-1175 2175);
DISPLAY INVISIBLE (-1175 2175);
FORCEPROP 1 LAST HDL_TAP TRUE
J 0
(-850 2000);
DISPLAY 0.872340 (-850 2000);
DISPLAY INVISIBLE (-850 2000);
FORCEPROP 1 LAST PATH I76
J 0
(-1177 2125);
DISPLAY 0.872340 (-1177 2125);
PAINT GREEN (-1177 2125);
DISPLAY INVISIBLE (-1177 2125);
FORCEADD TAP..1
(-1175 2175);
FORCEPROP 3 LASTPIN (-1225 2175) SIG_NAME M_C_CPU1_SB_DQ<24>
J 0
(-1215 2185);
DISPLAY 0.659574 (-1215 2185);
PAINT MONO (-1215 2185);
DISPLAY INVISIBLE (-1215 2185);
FORCEPROP 1 LASTPIN (-1225 2175) BN 24
J 0
(-1237 2183);
DISPLAY 0.680851 (-1237 2183);
PAINT GREEN (-1237 2183);
FORCEPROP 2 LAST CDS_LIB standard
J 0
(-1175 2175);
DISPLAY INVISIBLE (-1175 2175);
FORCEPROP 1 LAST BODY_TYPE PLUMBING
J 0
(-1175 2225);
DISPLAY 0.872340 (-1175 2225);
PAINT GREEN (-1175 2225);
DISPLAY INVISIBLE (-1175 2225);
FORCEPROP 1 LAST HDL_TAP TRUE
J 0
(-850 2050);
DISPLAY 0.872340 (-850 2050);
DISPLAY INVISIBLE (-850 2050);
FORCEPROP 1 LAST PATH I77
J 0
(-1177 2175);
DISPLAY 0.872340 (-1177 2175);
PAINT GREEN (-1177 2175);
DISPLAY INVISIBLE (-1177 2175);
FORCEADD TAP..1
(-1175 2225);
FORCEPROP 3 LASTPIN (-1225 2225) SIG_NAME M_C_CPU1_SB_DQ<25>
J 0
(-1215 2235);
DISPLAY 0.659574 (-1215 2235);
PAINT MONO (-1215 2235);
DISPLAY INVISIBLE (-1215 2235);
FORCEPROP 1 LASTPIN (-1225 2225) BN 25
J 0
(-1237 2233);
DISPLAY 0.680851 (-1237 2233);
PAINT GREEN (-1237 2233);
FORCEPROP 2 LAST CDS_LIB standard
J 0
(-1175 2225);
DISPLAY INVISIBLE (-1175 2225);
FORCEPROP 1 LAST BODY_TYPE PLUMBING
J 0
(-1175 2275);
DISPLAY 0.872340 (-1175 2275);
PAINT GREEN (-1175 2275);
DISPLAY INVISIBLE (-1175 2275);
FORCEPROP 1 LAST HDL_TAP TRUE
J 0
(-850 2100);
DISPLAY 0.872340 (-850 2100);
DISPLAY INVISIBLE (-850 2100);
FORCEPROP 1 LAST PATH I78
J 0
(-1177 2225);
DISPLAY 0.872340 (-1177 2225);
PAINT GREEN (-1177 2225);
DISPLAY INVISIBLE (-1177 2225);
FORCEADD TAP..1
(-1175 2325);
FORCEPROP 3 LASTPIN (-1225 2325) SIG_NAME M_C_CPU1_SB_DQ<27>
J 0
(-1215 2335);
DISPLAY 0.659574 (-1215 2335);
PAINT MONO (-1215 2335);
DISPLAY INVISIBLE (-1215 2335);
FORCEPROP 1 LASTPIN (-1225 2325) BN 27
J 0
(-1237 2333);
DISPLAY 0.680851 (-1237 2333);
PAINT GREEN (-1237 2333);
FORCEPROP 2 LAST CDS_LIB standard
J 0
(-1175 2325);
DISPLAY INVISIBLE (-1175 2325);
FORCEPROP 1 LAST BODY_TYPE PLUMBING
J 0
(-1175 2375);
DISPLAY 0.872340 (-1175 2375);
PAINT GREEN (-1175 2375);
DISPLAY INVISIBLE (-1175 2375);
FORCEPROP 1 LAST HDL_TAP TRUE
J 0
(-850 2200);
DISPLAY 0.872340 (-850 2200);
DISPLAY INVISIBLE (-850 2200);
FORCEPROP 1 LAST PATH I79
J 0
(-1177 2325);
DISPLAY 0.872340 (-1177 2325);
PAINT GREEN (-1177 2325);
DISPLAY INVISIBLE (-1177 2325);
FORCEADD OFFPAGE..1
(-3750 1825);
FORCEPROP 2 LAST $XR1 103 
J 0
(-4091 1825);
DISPLAY 0.638298 (-4091 1825);
PAINT MONO (-4091 1825);
FORCEPROP 2 LAST $XR0 53 
J 0
(-3971 1825);
DISPLAY 0.638298 (-3971 1825);
PAINT MONO (-3971 1825);
FORCEPROP 2 LAST CDS_LIB standard
J 0
(-3750 1825);
PAINT MONO (-3750 1825);
DISPLAY INVISIBLE (-3750 1825);
FORCEPROP 1 LAST OFFPAGE TRUE
J 0
(-3425 1700);
DISPLAY 0.872340 (-3425 1700);
DISPLAY INVISIBLE (-3425 1700);
FORCEPROP 1 LAST COMMENT_BODY TRUE
J 0
(-3625 1725);
DISPLAY 0.872340 (-3625 1725);
PAINT GREEN (-3625 1725);
DISPLAY INVISIBLE (-3625 1725);
FORCEPROP 2 LAST PATH I8
J 0
(-3700 1900);
DISPLAY 1.021277 (-3700 1900);
DISPLAY INVISIBLE (-3700 1900);
FORCEADD TAP..1
(-1175 2275);
FORCEPROP 3 LASTPIN (-1225 2275) SIG_NAME M_C_CPU1_SB_DQ<26>
J 0
(-1215 2285);
DISPLAY 0.659574 (-1215 2285);
PAINT MONO (-1215 2285);
DISPLAY INVISIBLE (-1215 2285);
FORCEPROP 1 LASTPIN (-1225 2275) BN 26
J 0
(-1237 2283);
DISPLAY 0.680851 (-1237 2283);
PAINT GREEN (-1237 2283);
FORCEPROP 2 LAST CDS_LIB standard
J 0
(-1175 2275);
DISPLAY INVISIBLE (-1175 2275);
FORCEPROP 1 LAST BODY_TYPE PLUMBING
J 0
(-1175 2325);
DISPLAY 0.872340 (-1175 2325);
PAINT GREEN (-1175 2325);
DISPLAY INVISIBLE (-1175 2325);
FORCEPROP 1 LAST HDL_TAP TRUE
J 0
(-850 2150);
DISPLAY 0.872340 (-850 2150);
DISPLAY INVISIBLE (-850 2150);
FORCEPROP 1 LAST PATH I80
J 0
(-1177 2275);
DISPLAY 0.872340 (-1177 2275);
PAINT GREEN (-1177 2275);
DISPLAY INVISIBLE (-1177 2275);
FORCEADD TAP..1
(-1175 2375);
FORCEPROP 3 LASTPIN (-1225 2375) SIG_NAME M_C_CPU1_SB_DQ<28>
J 0
(-1215 2385);
DISPLAY 0.659574 (-1215 2385);
PAINT MONO (-1215 2385);
DISPLAY INVISIBLE (-1215 2385);
FORCEPROP 1 LASTPIN (-1225 2375) BN 28
J 0
(-1237 2383);
DISPLAY 0.680851 (-1237 2383);
PAINT GREEN (-1237 2383);
FORCEPROP 2 LAST CDS_LIB standard
J 0
(-1175 2375);
DISPLAY INVISIBLE (-1175 2375);
FORCEPROP 1 LAST BODY_TYPE PLUMBING
J 0
(-1175 2425);
DISPLAY 0.872340 (-1175 2425);
PAINT GREEN (-1175 2425);
DISPLAY INVISIBLE (-1175 2425);
FORCEPROP 1 LAST HDL_TAP TRUE
J 0
(-850 2250);
DISPLAY 0.872340 (-850 2250);
DISPLAY INVISIBLE (-850 2250);
FORCEPROP 1 LAST PATH I81
J 0
(-1177 2375);
DISPLAY 0.872340 (-1177 2375);
PAINT GREEN (-1177 2375);
DISPLAY INVISIBLE (-1177 2375);
FORCEADD TAP..1
(-1175 2425);
FORCEPROP 3 LASTPIN (-1225 2425) SIG_NAME M_C_CPU1_SB_DQ<29>
J 0
(-1215 2435);
DISPLAY 0.659574 (-1215 2435);
PAINT MONO (-1215 2435);
DISPLAY INVISIBLE (-1215 2435);
FORCEPROP 1 LASTPIN (-1225 2425) BN 29
J 0
(-1237 2433);
DISPLAY 0.680851 (-1237 2433);
PAINT GREEN (-1237 2433);
FORCEPROP 2 LAST CDS_LIB standard
J 0
(-1175 2425);
DISPLAY INVISIBLE (-1175 2425);
FORCEPROP 1 LAST BODY_TYPE PLUMBING
J 0
(-1175 2475);
DISPLAY 0.872340 (-1175 2475);
PAINT GREEN (-1175 2475);
DISPLAY INVISIBLE (-1175 2475);
FORCEPROP 1 LAST HDL_TAP TRUE
J 0
(-850 2300);
DISPLAY 0.872340 (-850 2300);
DISPLAY INVISIBLE (-850 2300);
FORCEPROP 1 LAST PATH I82
J 0
(-1177 2425);
DISPLAY 0.872340 (-1177 2425);
PAINT GREEN (-1177 2425);
DISPLAY INVISIBLE (-1177 2425);
FORCEADD TAP..1
(-1175 2525);
FORCEPROP 3 LASTPIN (-1225 2525) SIG_NAME M_C_CPU1_SB_DQ<31>
J 0
(-1215 2535);
DISPLAY 0.659574 (-1215 2535);
PAINT MONO (-1215 2535);
DISPLAY INVISIBLE (-1215 2535);
FORCEPROP 1 LASTPIN (-1225 2525) BN 31
J 0
(-1237 2533);
DISPLAY 0.680851 (-1237 2533);
PAINT GREEN (-1237 2533);
FORCEPROP 2 LAST CDS_LIB standard
J 0
(-1175 2525);
DISPLAY INVISIBLE (-1175 2525);
FORCEPROP 1 LAST BODY_TYPE PLUMBING
J 0
(-1175 2575);
DISPLAY 0.872340 (-1175 2575);
PAINT GREEN (-1175 2575);
DISPLAY INVISIBLE (-1175 2575);
FORCEPROP 1 LAST HDL_TAP TRUE
J 0
(-850 2400);
DISPLAY 0.872340 (-850 2400);
DISPLAY INVISIBLE (-850 2400);
FORCEPROP 1 LAST PATH I83
J 0
(-1177 2525);
DISPLAY 0.872340 (-1177 2525);
PAINT GREEN (-1177 2525);
DISPLAY INVISIBLE (-1177 2525);
FORCEADD TAP..1
(-1175 2475);
FORCEPROP 3 LASTPIN (-1225 2475) SIG_NAME M_C_CPU1_SB_DQ<30>
J 0
(-1215 2485);
DISPLAY 0.659574 (-1215 2485);
PAINT MONO (-1215 2485);
DISPLAY INVISIBLE (-1215 2485);
FORCEPROP 1 LASTPIN (-1225 2475) BN 30
J 0
(-1237 2483);
DISPLAY 0.680851 (-1237 2483);
PAINT GREEN (-1237 2483);
FORCEPROP 2 LAST CDS_LIB standard
J 0
(-1175 2475);
DISPLAY INVISIBLE (-1175 2475);
FORCEPROP 1 LAST BODY_TYPE PLUMBING
J 0
(-1175 2525);
DISPLAY 0.872340 (-1175 2525);
PAINT GREEN (-1175 2525);
DISPLAY INVISIBLE (-1175 2525);
FORCEPROP 1 LAST HDL_TAP TRUE
J 0
(-850 2350);
DISPLAY 0.872340 (-850 2350);
DISPLAY INVISIBLE (-850 2350);
FORCEPROP 1 LAST PATH I84
J 0
(-1177 2475);
DISPLAY 0.872340 (-1177 2475);
PAINT GREEN (-1177 2475);
DISPLAY INVISIBLE (-1177 2475);
FORCEADD TAP..1
(-1175 2625);
FORCEPROP 3 LASTPIN (-1225 2625) SIG_NAME M_C_CPU1_SA_DQ<0>
J 0
(-1215 2635);
DISPLAY 0.659574 (-1215 2635);
PAINT MONO (-1215 2635);
DISPLAY INVISIBLE (-1215 2635);
FORCEPROP 1 LASTPIN (-1225 2625) BN 0
J 0
(-1237 2633);
DISPLAY 0.680851 (-1237 2633);
PAINT GREEN (-1237 2633);
FORCEPROP 2 LAST CDS_LIB standard
J 0
(-1175 2625);
PAINT MONO (-1175 2625);
DISPLAY INVISIBLE (-1175 2625);
FORCEPROP 1 LAST BODY_TYPE PLUMBING
J 0
(-1175 2675);
DISPLAY 0.872340 (-1175 2675);
PAINT GREEN (-1175 2675);
DISPLAY INVISIBLE (-1175 2675);
FORCEPROP 1 LAST HDL_TAP TRUE
J 0
(-850 2500);
DISPLAY 0.872340 (-850 2500);
DISPLAY INVISIBLE (-850 2500);
FORCEPROP 1 LAST PATH I85
J 0
(-1177 2625);
DISPLAY 0.872340 (-1177 2625);
PAINT GREEN (-1177 2625);
DISPLAY INVISIBLE (-1177 2625);
FORCEADD TAP..1
(-1175 2675);
FORCEPROP 3 LASTPIN (-1225 2675) SIG_NAME M_C_CPU1_SA_DQ<1>
J 0
(-1215 2685);
DISPLAY 0.659574 (-1215 2685);
PAINT MONO (-1215 2685);
DISPLAY INVISIBLE (-1215 2685);
FORCEPROP 1 LASTPIN (-1225 2675) BN 1
J 0
(-1237 2683);
DISPLAY 0.680851 (-1237 2683);
PAINT GREEN (-1237 2683);
FORCEPROP 2 LAST CDS_LIB standard
J 0
(-1175 2675);
PAINT MONO (-1175 2675);
DISPLAY INVISIBLE (-1175 2675);
FORCEPROP 1 LAST BODY_TYPE PLUMBING
J 0
(-1175 2725);
DISPLAY 0.872340 (-1175 2725);
PAINT GREEN (-1175 2725);
DISPLAY INVISIBLE (-1175 2725);
FORCEPROP 1 LAST HDL_TAP TRUE
J 0
(-850 2550);
DISPLAY 0.872340 (-850 2550);
DISPLAY INVISIBLE (-850 2550);
FORCEPROP 1 LAST PATH I86
J 0
(-1177 2675);
DISPLAY 0.872340 (-1177 2675);
PAINT GREEN (-1177 2675);
DISPLAY INVISIBLE (-1177 2675);
FORCEADD TAP..1
(-1175 2725);
FORCEPROP 3 LASTPIN (-1225 2725) SIG_NAME M_C_CPU1_SA_DQ<2>
J 0
(-1215 2735);
DISPLAY 0.659574 (-1215 2735);
PAINT MONO (-1215 2735);
DISPLAY INVISIBLE (-1215 2735);
FORCEPROP 1 LASTPIN (-1225 2725) BN 2
J 0
(-1237 2733);
DISPLAY 0.680851 (-1237 2733);
PAINT GREEN (-1237 2733);
FORCEPROP 2 LAST CDS_LIB standard
J 0
(-1175 2725);
PAINT MONO (-1175 2725);
DISPLAY INVISIBLE (-1175 2725);
FORCEPROP 1 LAST BODY_TYPE PLUMBING
J 0
(-1175 2775);
DISPLAY 0.872340 (-1175 2775);
PAINT GREEN (-1175 2775);
DISPLAY INVISIBLE (-1175 2775);
FORCEPROP 1 LAST HDL_TAP TRUE
J 0
(-850 2600);
DISPLAY 0.872340 (-850 2600);
DISPLAY INVISIBLE (-850 2600);
FORCEPROP 1 LAST PATH I87
J 0
(-1177 2725);
DISPLAY 0.872340 (-1177 2725);
PAINT GREEN (-1177 2725);
DISPLAY INVISIBLE (-1177 2725);
FORCEADD TAP..1
(-1175 2775);
FORCEPROP 3 LASTPIN (-1225 2775) SIG_NAME M_C_CPU1_SA_DQ<3>
J 0
(-1215 2785);
DISPLAY 0.659574 (-1215 2785);
PAINT MONO (-1215 2785);
DISPLAY INVISIBLE (-1215 2785);
FORCEPROP 1 LASTPIN (-1225 2775) BN 3
J 0
(-1237 2783);
DISPLAY 0.680851 (-1237 2783);
PAINT GREEN (-1237 2783);
FORCEPROP 2 LAST CDS_LIB standard
J 0
(-1175 2775);
PAINT MONO (-1175 2775);
DISPLAY INVISIBLE (-1175 2775);
FORCEPROP 1 LAST BODY_TYPE PLUMBING
J 0
(-1175 2825);
DISPLAY 0.872340 (-1175 2825);
PAINT GREEN (-1175 2825);
DISPLAY INVISIBLE (-1175 2825);
FORCEPROP 1 LAST HDL_TAP TRUE
J 0
(-850 2650);
DISPLAY 0.872340 (-850 2650);
DISPLAY INVISIBLE (-850 2650);
FORCEPROP 1 LAST PATH I88
J 0
(-1177 2775);
DISPLAY 0.872340 (-1177 2775);
PAINT GREEN (-1177 2775);
DISPLAY INVISIBLE (-1177 2775);
FORCEADD TAP..1
(-1175 2825);
FORCEPROP 3 LASTPIN (-1225 2825) SIG_NAME M_C_CPU1_SA_DQ<4>
J 0
(-1215 2835);
DISPLAY 0.659574 (-1215 2835);
PAINT MONO (-1215 2835);
DISPLAY INVISIBLE (-1215 2835);
FORCEPROP 1 LASTPIN (-1225 2825) BN 4
J 0
(-1237 2833);
DISPLAY 0.680851 (-1237 2833);
PAINT GREEN (-1237 2833);
FORCEPROP 2 LAST CDS_LIB standard
J 0
(-1175 2825);
PAINT MONO (-1175 2825);
DISPLAY INVISIBLE (-1175 2825);
FORCEPROP 1 LAST BODY_TYPE PLUMBING
J 0
(-1175 2875);
DISPLAY 0.872340 (-1175 2875);
PAINT GREEN (-1175 2875);
DISPLAY INVISIBLE (-1175 2875);
FORCEPROP 1 LAST HDL_TAP TRUE
J 0
(-850 2700);
DISPLAY 0.872340 (-850 2700);
DISPLAY INVISIBLE (-850 2700);
FORCEPROP 1 LAST PATH I89
J 0
(-1177 2825);
DISPLAY 0.872340 (-1177 2825);
PAINT GREEN (-1177 2825);
DISPLAY INVISIBLE (-1177 2825);
FORCEADD OFFPAGE..1
(-3650 1675);
FORCEPROP 2 LAST $XR0 102 
J 0
(-3902 1675);
DISPLAY 0.638298 (-3902 1675);
PAINT MONO (-3902 1675);
FORCEPROP 2 LAST CDS_LIB standard
J 0
(-3650 1675);
PAINT MONO (-3650 1675);
DISPLAY INVISIBLE (-3650 1675);
FORCEPROP 1 LAST OFFPAGE TRUE
J 0
(-3325 1550);
DISPLAY 0.872340 (-3325 1550);
DISPLAY INVISIBLE (-3325 1550);
FORCEPROP 1 LAST COMMENT_BODY TRUE
J 0
(-3525 1575);
DISPLAY 0.872340 (-3525 1575);
PAINT GREEN (-3525 1575);
DISPLAY INVISIBLE (-3525 1575);
FORCEPROP 2 LAST PATH I9
J 0
(-3600 1750);
DISPLAY 1.021277 (-3600 1750);
DISPLAY INVISIBLE (-3600 1750);
FORCEADD TAP..1
(-1175 2875);
FORCEPROP 3 LASTPIN (-1225 2875) SIG_NAME M_C_CPU1_SA_DQ<5>
J 0
(-1215 2885);
DISPLAY 0.659574 (-1215 2885);
PAINT MONO (-1215 2885);
DISPLAY INVISIBLE (-1215 2885);
FORCEPROP 1 LASTPIN (-1225 2875) BN 5
J 0
(-1237 2883);
DISPLAY 0.680851 (-1237 2883);
PAINT GREEN (-1237 2883);
FORCEPROP 2 LAST CDS_LIB standard
J 0
(-1175 2875);
PAINT MONO (-1175 2875);
DISPLAY INVISIBLE (-1175 2875);
FORCEPROP 1 LAST BODY_TYPE PLUMBING
J 0
(-1175 2925);
DISPLAY 0.872340 (-1175 2925);
PAINT GREEN (-1175 2925);
DISPLAY INVISIBLE (-1175 2925);
FORCEPROP 1 LAST HDL_TAP TRUE
J 0
(-850 2750);
DISPLAY 0.872340 (-850 2750);
DISPLAY INVISIBLE (-850 2750);
FORCEPROP 1 LAST PATH I90
J 0
(-1177 2875);
DISPLAY 0.872340 (-1177 2875);
PAINT GREEN (-1177 2875);
DISPLAY INVISIBLE (-1177 2875);
FORCEADD TAP..1
(-1175 2925);
FORCEPROP 3 LASTPIN (-1225 2925) SIG_NAME M_C_CPU1_SA_DQ<6>
J 0
(-1215 2935);
DISPLAY 0.659574 (-1215 2935);
PAINT MONO (-1215 2935);
DISPLAY INVISIBLE (-1215 2935);
FORCEPROP 1 LASTPIN (-1225 2925) BN 6
J 0
(-1237 2933);
DISPLAY 0.680851 (-1237 2933);
PAINT GREEN (-1237 2933);
FORCEPROP 2 LAST CDS_LIB standard
J 0
(-1175 2925);
PAINT MONO (-1175 2925);
DISPLAY INVISIBLE (-1175 2925);
FORCEPROP 1 LAST BODY_TYPE PLUMBING
J 0
(-1175 2975);
DISPLAY 0.872340 (-1175 2975);
PAINT GREEN (-1175 2975);
DISPLAY INVISIBLE (-1175 2975);
FORCEPROP 1 LAST HDL_TAP TRUE
J 0
(-850 2800);
DISPLAY 0.872340 (-850 2800);
DISPLAY INVISIBLE (-850 2800);
FORCEPROP 1 LAST PATH I91
J 0
(-1177 2925);
DISPLAY 0.872340 (-1177 2925);
PAINT GREEN (-1177 2925);
DISPLAY INVISIBLE (-1177 2925);
FORCEADD TAP..1
(-1175 2975);
FORCEPROP 3 LASTPIN (-1225 2975) SIG_NAME M_C_CPU1_SA_DQ<7>
J 0
(-1215 2985);
DISPLAY 0.659574 (-1215 2985);
PAINT MONO (-1215 2985);
DISPLAY INVISIBLE (-1215 2985);
FORCEPROP 1 LASTPIN (-1225 2975) BN 7
J 0
(-1237 2983);
DISPLAY 0.680851 (-1237 2983);
PAINT GREEN (-1237 2983);
FORCEPROP 2 LAST CDS_LIB standard
J 0
(-1175 2975);
PAINT MONO (-1175 2975);
DISPLAY INVISIBLE (-1175 2975);
FORCEPROP 1 LAST BODY_TYPE PLUMBING
J 0
(-1175 3025);
DISPLAY 0.872340 (-1175 3025);
PAINT GREEN (-1175 3025);
DISPLAY INVISIBLE (-1175 3025);
FORCEPROP 1 LAST HDL_TAP TRUE
J 0
(-850 2850);
DISPLAY 0.872340 (-850 2850);
DISPLAY INVISIBLE (-850 2850);
FORCEPROP 1 LAST PATH I92
J 0
(-1177 2975);
DISPLAY 0.872340 (-1177 2975);
PAINT GREEN (-1177 2975);
DISPLAY INVISIBLE (-1177 2975);
FORCEADD TAP..1
(-1175 3025);
FORCEPROP 3 LASTPIN (-1225 3025) SIG_NAME M_C_CPU1_SA_DQ<8>
J 0
(-1215 3035);
DISPLAY 0.659574 (-1215 3035);
PAINT MONO (-1215 3035);
DISPLAY INVISIBLE (-1215 3035);
FORCEPROP 1 LASTPIN (-1225 3025) BN 8
J 0
(-1237 3033);
DISPLAY 0.680851 (-1237 3033);
PAINT GREEN (-1237 3033);
FORCEPROP 2 LAST CDS_LIB standard
J 0
(-1175 3025);
PAINT MONO (-1175 3025);
DISPLAY INVISIBLE (-1175 3025);
FORCEPROP 1 LAST BODY_TYPE PLUMBING
J 0
(-1175 3075);
DISPLAY 0.872340 (-1175 3075);
PAINT GREEN (-1175 3075);
DISPLAY INVISIBLE (-1175 3075);
FORCEPROP 1 LAST HDL_TAP TRUE
J 0
(-850 2900);
DISPLAY 0.872340 (-850 2900);
DISPLAY INVISIBLE (-850 2900);
FORCEPROP 1 LAST PATH I93
J 0
(-1177 3025);
DISPLAY 0.872340 (-1177 3025);
PAINT GREEN (-1177 3025);
DISPLAY INVISIBLE (-1177 3025);
FORCEADD TAP..1
(-1175 3075);
FORCEPROP 3 LASTPIN (-1225 3075) SIG_NAME M_C_CPU1_SA_DQ<9>
J 0
(-1215 3085);
DISPLAY 0.659574 (-1215 3085);
PAINT MONO (-1215 3085);
DISPLAY INVISIBLE (-1215 3085);
FORCEPROP 1 LASTPIN (-1225 3075) BN 9
J 0
(-1237 3083);
DISPLAY 0.680851 (-1237 3083);
PAINT GREEN (-1237 3083);
FORCEPROP 2 LAST CDS_LIB standard
J 0
(-1175 3075);
PAINT MONO (-1175 3075);
DISPLAY INVISIBLE (-1175 3075);
FORCEPROP 1 LAST BODY_TYPE PLUMBING
J 0
(-1175 3125);
DISPLAY 0.872340 (-1175 3125);
PAINT GREEN (-1175 3125);
DISPLAY INVISIBLE (-1175 3125);
FORCEPROP 1 LAST HDL_TAP TRUE
J 0
(-850 2950);
DISPLAY 0.872340 (-850 2950);
DISPLAY INVISIBLE (-850 2950);
FORCEPROP 1 LAST PATH I94
J 0
(-1177 3075);
DISPLAY 0.872340 (-1177 3075);
PAINT GREEN (-1177 3075);
DISPLAY INVISIBLE (-1177 3075);
FORCEADD TAP..1
(-1175 3125);
FORCEPROP 3 LASTPIN (-1225 3125) SIG_NAME M_C_CPU1_SA_DQ<10>
J 0
(-1215 3135);
DISPLAY 0.659574 (-1215 3135);
PAINT MONO (-1215 3135);
DISPLAY INVISIBLE (-1215 3135);
FORCEPROP 1 LASTPIN (-1225 3125) BN 10
J 0
(-1237 3133);
DISPLAY 0.680851 (-1237 3133);
PAINT GREEN (-1237 3133);
FORCEPROP 2 LAST CDS_LIB standard
J 0
(-1175 3125);
PAINT MONO (-1175 3125);
DISPLAY INVISIBLE (-1175 3125);
FORCEPROP 1 LAST BODY_TYPE PLUMBING
J 0
(-1175 3175);
DISPLAY 0.872340 (-1175 3175);
PAINT GREEN (-1175 3175);
DISPLAY INVISIBLE (-1175 3175);
FORCEPROP 1 LAST HDL_TAP TRUE
J 0
(-850 3000);
DISPLAY 0.872340 (-850 3000);
DISPLAY INVISIBLE (-850 3000);
FORCEPROP 1 LAST PATH I95
J 0
(-1177 3125);
DISPLAY 0.872340 (-1177 3125);
PAINT GREEN (-1177 3125);
DISPLAY INVISIBLE (-1177 3125);
FORCEADD TAP..1
(-1175 3175);
FORCEPROP 3 LASTPIN (-1225 3175) SIG_NAME M_C_CPU1_SA_DQ<11>
J 0
(-1215 3185);
DISPLAY 0.659574 (-1215 3185);
PAINT MONO (-1215 3185);
DISPLAY INVISIBLE (-1215 3185);
FORCEPROP 1 LASTPIN (-1225 3175) BN 11
J 0
(-1237 3183);
DISPLAY 0.680851 (-1237 3183);
PAINT GREEN (-1237 3183);
FORCEPROP 2 LAST CDS_LIB standard
J 0
(-1175 3175);
PAINT MONO (-1175 3175);
DISPLAY INVISIBLE (-1175 3175);
FORCEPROP 1 LAST BODY_TYPE PLUMBING
J 0
(-1175 3225);
DISPLAY 0.872340 (-1175 3225);
PAINT GREEN (-1175 3225);
DISPLAY INVISIBLE (-1175 3225);
FORCEPROP 1 LAST HDL_TAP TRUE
J 0
(-850 3050);
DISPLAY 0.872340 (-850 3050);
DISPLAY INVISIBLE (-850 3050);
FORCEPROP 1 LAST PATH I96
J 0
(-1177 3175);
DISPLAY 0.872340 (-1177 3175);
PAINT GREEN (-1177 3175);
DISPLAY INVISIBLE (-1177 3175);
FORCEADD TAP..1
(-1175 3225);
FORCEPROP 3 LASTPIN (-1225 3225) SIG_NAME M_C_CPU1_SA_DQ<12>
J 0
(-1215 3235);
DISPLAY 0.659574 (-1215 3235);
PAINT MONO (-1215 3235);
DISPLAY INVISIBLE (-1215 3235);
FORCEPROP 1 LASTPIN (-1225 3225) BN 12
J 0
(-1237 3233);
DISPLAY 0.680851 (-1237 3233);
PAINT GREEN (-1237 3233);
FORCEPROP 2 LAST CDS_LIB standard
J 0
(-1175 3225);
PAINT MONO (-1175 3225);
DISPLAY INVISIBLE (-1175 3225);
FORCEPROP 1 LAST BODY_TYPE PLUMBING
J 0
(-1175 3275);
DISPLAY 0.872340 (-1175 3275);
PAINT GREEN (-1175 3275);
DISPLAY INVISIBLE (-1175 3275);
FORCEPROP 1 LAST HDL_TAP TRUE
J 0
(-850 3100);
DISPLAY 0.872340 (-850 3100);
DISPLAY INVISIBLE (-850 3100);
FORCEPROP 1 LAST PATH I97
J 0
(-1177 3225);
DISPLAY 0.872340 (-1177 3225);
PAINT GREEN (-1177 3225);
DISPLAY INVISIBLE (-1177 3225);
FORCEADD TAP..1
(-1175 3325);
FORCEPROP 3 LASTPIN (-1225 3325) SIG_NAME M_C_CPU1_SA_DQ<14>
J 0
(-1215 3335);
DISPLAY 0.659574 (-1215 3335);
PAINT MONO (-1215 3335);
DISPLAY INVISIBLE (-1215 3335);
FORCEPROP 1 LASTPIN (-1225 3325) BN 14
J 0
(-1237 3333);
DISPLAY 0.680851 (-1237 3333);
PAINT GREEN (-1237 3333);
FORCEPROP 2 LAST CDS_LIB standard
J 0
(-1175 3325);
PAINT MONO (-1175 3325);
DISPLAY INVISIBLE (-1175 3325);
FORCEPROP 1 LAST BODY_TYPE PLUMBING
J 0
(-1175 3375);
DISPLAY 0.872340 (-1175 3375);
PAINT GREEN (-1175 3375);
DISPLAY INVISIBLE (-1175 3375);
FORCEPROP 1 LAST HDL_TAP TRUE
J 0
(-850 3200);
DISPLAY 0.872340 (-850 3200);
DISPLAY INVISIBLE (-850 3200);
FORCEPROP 1 LAST PATH I98
J 0
(-1177 3325);
DISPLAY 0.872340 (-1177 3325);
PAINT GREEN (-1177 3325);
DISPLAY INVISIBLE (-1177 3325);
FORCEADD TAP..1
(-1175 3275);
FORCEPROP 3 LASTPIN (-1225 3275) SIG_NAME M_C_CPU1_SA_DQ<13>
J 0
(-1215 3285);
DISPLAY 0.659574 (-1215 3285);
PAINT MONO (-1215 3285);
DISPLAY INVISIBLE (-1215 3285);
FORCEPROP 1 LASTPIN (-1225 3275) BN 13
J 0
(-1237 3283);
DISPLAY 0.680851 (-1237 3283);
PAINT GREEN (-1237 3283);
FORCEPROP 2 LAST CDS_LIB standard
J 0
(-1175 3275);
PAINT MONO (-1175 3275);
DISPLAY INVISIBLE (-1175 3275);
FORCEPROP 1 LAST BODY_TYPE PLUMBING
J 0
(-1175 3325);
DISPLAY 0.872340 (-1175 3325);
PAINT GREEN (-1175 3325);
DISPLAY INVISIBLE (-1175 3325);
FORCEPROP 1 LAST HDL_TAP TRUE
J 0
(-850 3150);
DISPLAY 0.872340 (-850 3150);
DISPLAY INVISIBLE (-850 3150);
FORCEPROP 1 LAST PATH I99
J 0
(-1177 3275);
DISPLAY 0.872340 (-1177 3275);
PAINT GREEN (-1177 3275);
DISPLAY INVISIBLE (-1177 3275);
FORCEADD CAD_NOTE..1
(675 -275);
FORCEPROP 0 LAST S1 PLACE THE BYPASS CAPS CLOSE TO DIMM
J 0
(550 -400);
DISPLAY 1.021277 (550 -400);
PAINT WHITE (550 -400);
FORCEPROP 2 LAST CDS_LIB logical_power
J 0
(675 -275);
PAINT MONO (675 -275);
DISPLAY INVISIBLE (675 -275);
FORCEPROP 1 LAST COMMENT_BODY TRUE
J 0
(700 -175);
DISPLAY 0.978723 (700 -175);
DISPLAY INVISIBLE (700 -175);
FORCEADD QUANTA_TITLE_BLOCK_C..1
(5150 -1575);
FORCEPROP 0 LAST CDS_CON_LAST_MODIFIED Fri Aug 25 14:01:22 2023
J 0
(3265 -1560);
PAINT MONO (3265 -1560);
DISPLAY INVISIBLE (3265 -1560);
FORCEPROP 1 LAST CUSTOM_TXT_CDS <CON_LAST_MODIFIED>
J 0
(3265 -1560);
DISPLAY 0.978723 (3265 -1560);
FORCEPROP 2 LAST CUSTOM_TXT_CDS <XR_PAGE_TITLE>
J 0
(-2740 3675);
DISPLAY 0.638298 (-2740 3675);
PAINT PINK (-2740 3675);
DISPLAY INVISIBLE (-2740 3675);
FORCEPROP 2 LAST CUSTOM_TXT_CDS <Q_NUMBER>
J 0
(3747 -1472);
DISPLAY 1.212766 (3747 -1472);
FORCEPROP 1 LAST CUSTOM_TXT_CDS <NAME_2>
J 0
(1975 -1525);
FORCEPROP 1 LAST CUSTOM_TXT_CDS <NAME_1>
J 0
(1975 -1400);
FORCEPROP 1 LAST CUSTOM_TXT_CDS <Q_PROJ>
J 0
(2768 -1473);
DISPLAY 1.212766 (2768 -1473);
FORCEPROP 1 LAST CUSTOM_TXT_CDS <Q_REV>
J 0
(4966 -1472);
DISPLAY 1.212766 (4966 -1472);
FORCEPROP 1 LAST CUSTOM_TXT_CDS <CON_PAGE_NUM> OF <CON_TOTAL_PAGES>
J 0
(4704 -1557);
DISPLAY 0.978723 (4704 -1557);
FORCEPROP 1 LAST Q_TITLE DDR5 - CPU1 CHC DIMM1(YELLOW)
J 0
(-4216 -1549);
DISPLAY 2.446809 (-4216 -1549);
PAINT GREEN (-4216 -1549);
FORCEPROP 1 LAST Q_DEPT 
J 1
(1387 -1526);
DISPLAY 1.957447 (1387 -1526);
PAINT GREEN (1387 -1526);
FORCEPROP 2 LAST CDS_XR_PAGE_TITLE CR-102 : @S9S_MB_2U_LIB.S9S_MB_2U(SCH_1):PAGE102
J 0
(-2740 3675);
DISPLAY 0.638298 (-2740 3675);
PAINT PINK (-2740 3675);
DISPLAY INVISIBLE (-2740 3675);
FORCEPROP 1 LAST COMMENT_BODY TRUE
J 0
(5162 -1588);
DISPLAY 0.978723 (5162 -1588);
PAINT GREEN (5162 -1588);
DISPLAY INVISIBLE (5162 -1588);
FORCEPROP 2 LAST CDS_LIB pure_quanta
J 0
(5150 -1575);
PAINT MONO (5150 -1575);
DISPLAY INVISIBLE (5150 -1575);
FORCEPROP 1 LAST CDS_LMAN_SYM_OUTLINE -9475,6775,100,-125
J 0
(5150 -1575);
DISPLAY 0.468085 (5150 -1575);
PAINT GREEN (5150 -1575);
DISPLAY INVISIBLE (5150 -1575);
FORCEPROP 2 LAST PAGE_BORDER TRUE
J 0
(-2740 3675);
DISPLAY 0.638298 (-2740 3675);
PAINT PINK (-2740 3675);
DISPLAY INVISIBLE (-2740 3675);
WIRE 17 -1 (-1125 4150)(-1125 4200);
WIRE 17 -1 (-1125 4100)(-1125 4150);
WIRE 17 -1 (-1125 4200)(-400 4200);
FORCEPROP 2 LAST SIG_NAME M_C_CPU1_SA_DQ<31:0>
J 0
(-1060 4210);
DISPLAY 0.680851 (-1060 4210);
PAINT WHITE (-1060 4210);
WIRE 17 -1 (-2875 2650)(-2875 2700);
WIRE 17 -1 (-2875 2600)(-2875 2650);
WIRE 17 -1 (-2875 2700)(-2875 2750);
WIRE 17 -1 (-2875 2750)(-2875 2800);
WIRE 17 -1 (-2875 2550)(-2875 2600);
WIRE 17 -1 (-2875 2500)(-2875 2550);
WIRE 17 -1 (-3700 2800)(-2875 2800);
FORCEPROP 2 LAST SIG_NAME M_C_CPU1_SA_CB<7:0>
J 0
(-3610 2810);
DISPLAY 0.680851 (-3610 2810);
PAINT WHITE (-3610 2810);
WIRE 17 -1 (-2875 2450)(-2875 2500);
WIRE 17 -1 (-2875 2300)(-2875 2350);
WIRE 17 -1 (-2875 2250)(-2875 2300);
WIRE 17 -1 (-3700 2350)(-2875 2350);
FORCEPROP 2 LAST SIG_NAME M_C_CPU1_SB_CB<7:0>
J 0
(-3610 2360);
DISPLAY 0.680851 (-3610 2360);
PAINT WHITE (-3610 2360);
WIRE 17 -1 (-2875 3900)(-2875 3950);
WIRE 17 -1 (-2875 3950)(-2875 4000);
WIRE 17 -1 (-2875 4000)(-2875 4050);
WIRE 17 -1 (-2875 4050)(-2875 4100);
WIRE 17 -1 (-2875 4100)(-2875 4150);
WIRE 17 -1 (-2875 4150)(-2875 4200);
WIRE 17 -1 (-3700 4200)(-2875 4200);
FORCEPROP 2 LAST SIG_NAME M_C_CPU1_SA_CA<6:0>
J 0
(-3610 4210);
DISPLAY 0.680851 (-3610 4210);
PAINT WHITE (-3610 4210);
WIRE 17 -1 (-2875 3500)(-2875 3550);
WIRE 17 -1 (-2875 3550)(-2875 3600);
WIRE 17 -1 (-2875 3600)(-2875 3650);
WIRE 17 -1 (-2875 3650)(-2875 3700);
WIRE 17 -1 (-2875 3700)(-2875 3750);
WIRE 17 -1 (-2875 3750)(-2875 3800);
WIRE 17 -1 (-3700 3800)(-2875 3800);
FORCEPROP 2 LAST SIG_NAME M_C_CPU1_SB_CA<6:0>
J 0
(-3610 3810);
DISPLAY 0.680851 (-3610 3810);
PAINT WHITE (-3610 3810);
WIRE 17 -1 (-2875 2200)(-2875 2250);
WIRE 17 -1 (-2875 2150)(-2875 2200);
WIRE 17 -1 (-2875 2100)(-2875 2150);
WIRE 17 -1 (-2875 2050)(-2875 2100);
WIRE 17 -1 (-2875 2000)(-2875 2050);
WIRE 17 -1 (-1125 4050)(-1125 4100);
WIRE 17 -1 (-1125 4000)(-1125 4050);
WIRE 17 -1 (-1125 3950)(-1125 4000);
WIRE 17 -1 (-1125 3900)(-1125 3950);
WIRE 17 -1 (-1125 3850)(-1125 3900);
WIRE 17 -1 (-1125 3800)(-1125 3850);
WIRE 17 -1 (-1125 3750)(-1125 3800);
WIRE 17 -1 (-1125 3700)(-1125 3750);
WIRE 17 -1 (-1125 3650)(-1125 3700);
WIRE 17 -1 (-1125 3600)(-1125 3650);
WIRE 17 -1 (-1125 3550)(-1125 3600);
WIRE 17 -1 (-1125 3500)(-1125 3550);
WIRE 17 -1 (-1125 3450)(-1125 3500);
WIRE 17 -1 (-1125 3400)(-1125 3450);
WIRE 17 -1 (-1125 3350)(-1125 3400);
WIRE 17 -1 (-1125 3300)(-1125 3350);
WIRE 17 -1 (-1125 3250)(-1125 3300);
WIRE 17 -1 (-1125 3200)(-1125 3250);
WIRE 17 -1 (-1125 3150)(-1125 3200);
WIRE 17 -1 (-1125 3100)(-1125 3150);
WIRE 17 -1 (-1125 3050)(-1125 3100);
WIRE 17 -1 (-1125 3000)(-1125 3050);
WIRE 17 -1 (-1125 2950)(-1125 3000);
WIRE 17 -1 (-1125 2900)(-1125 2950);
WIRE 17 -1 (-1125 2850)(-1125 2900);
WIRE 17 -1 (-1125 2800)(-1125 2850);
WIRE 17 -1 (-1125 2750)(-1125 2800);
WIRE 17 -1 (-1125 2700)(-1125 2750);
WIRE 17 -1 (-1125 2650)(-1125 2700);
WIRE 17 -1 (-1125 2500)(-1125 2550);
WIRE 17 -1 (-1125 2450)(-1125 2500);
WIRE 17 -1 (-1125 2550)(-400 2550);
FORCEPROP 2 LAST SIG_NAME M_C_CPU1_SB_DQ<31:0>
J 0
(-1060 2560);
DISPLAY 0.680851 (-1060 2560);
PAINT WHITE (-1060 2560);
WIRE 17 -1 (-1125 2400)(-1125 2450);
WIRE 17 -1 (-1125 2300)(-1125 2350);
WIRE 17 -1 (-1125 2250)(-1125 2300);
WIRE 17 -1 (-1125 2350)(-1125 2400);
WIRE 17 -1 (-1125 2200)(-1125 2250);
WIRE 17 -1 (-1125 2150)(-1125 2200);
WIRE 17 -1 (-1125 2100)(-1125 2150);
WIRE 17 -1 (-1125 2050)(-1125 2100);
WIRE 17 -1 (-1125 2000)(-1125 2050);
WIRE 17 -1 (-1125 1950)(-1125 2000);
WIRE 17 -1 (-1125 1900)(-1125 1950);
WIRE 17 -1 (-1125 1850)(-1125 1900);
WIRE 17 -1 (-1125 1800)(-1125 1850);
WIRE 17 -1 (-1125 1750)(-1125 1800);
WIRE 17 -1 (-1125 1700)(-1125 1750);
WIRE 17 -1 (-1125 1650)(-1125 1700);
WIRE 17 -1 (-1125 1600)(-1125 1650);
WIRE 17 -1 (-1125 1550)(-1125 1600);
WIRE 17 -1 (-1125 1500)(-1125 1550);
WIRE 17 -1 (-1125 1450)(-1125 1500);
WIRE 17 -1 (-1125 1400)(-1125 1450);
WIRE 17 -1 (-1125 1350)(-1125 1400);
WIRE 17 -1 (-1125 1300)(-1125 1350);
WIRE 17 -1 (-1125 1250)(-1125 1300);
WIRE 17 -1 (-1125 1200)(-1125 1250);
WIRE 17 -1 (-1125 1150)(-1125 1200);
WIRE 17 -1 (-1125 1100)(-1125 1150);
WIRE 17 -1 (-1125 1050)(-1125 1100);
WIRE 17 -1 (-1125 1000)(-1125 1050);
WIRE 17 -1 (1625 2950)(1625 3050);
WIRE 17 -1 (1625 2850)(1625 2950);
WIRE 17 -1 (1625 3050)(1625 3150);
WIRE 17 -1 (1625 3150)(2650 3150);
FORCEPROP 2 LAST SIG_NAME M_C_CPU1_SB_DQS_DP<9:0>
J 0
(1865 3160);
DISPLAY 0.680851 (1865 3160);
PAINT WHITE (1865 3160);
WIRE 17 -1 (1625 2750)(1625 2850);
WIRE 17 -1 (1625 2650)(1625 2750);
WIRE 17 -1 (1625 2650)(1625 2550);
WIRE 17 -1 (1625 2450)(1625 2550);
WIRE 17 -1 (1625 2350)(1625 2450);
WIRE 17 -1 (1625 2250)(1625 2350);
WIRE 17 -1 (1625 3900)(1625 4000);
WIRE 17 -1 (1625 3800)(1625 3900);
WIRE 17 -1 (1625 4000)(1625 4100);
WIRE 17 -1 (1625 4100)(1625 4200);
WIRE 17 -1 (1625 3700)(1625 3800);
WIRE 17 -1 (1625 3700)(1625 3600);
WIRE 17 -1 (1625 4200)(2650 4200);
FORCEPROP 2 LAST SIG_NAME M_C_CPU1_SA_DQS_DP<9:0>
J 0
(1865 4210);
DISPLAY 0.680851 (1865 4210);
PAINT WHITE (1865 4210);
WIRE 17 -1 (1625 3500)(1625 3600);
WIRE 17 -1 (1625 3400)(1625 3500);
WIRE 17 -1 (1625 3300)(1625 3400);
WIRE 17 -1 (1800 2200)(1800 2300);
WIRE 17 -1 (1800 2300)(1800 2400);
WIRE 17 -1 (1800 2400)(1800 2500);
WIRE 17 -1 (1800 2600)(1800 2500);
WIRE 17 -1 (1800 2600)(1800 2700);
WIRE 17 -1 (1800 2700)(1800 2800);
WIRE 17 -1 (1800 2800)(1800 2900);
WIRE 17 -1 (1800 2900)(1800 3000);
WIRE 17 -1 (1800 3000)(1800 3100);
WIRE 17 -1 (1800 3100)(2650 3100);
FORCEPROP 2 LAST SIG_NAME M_C_CPU1_SB_DQS_DN<9:0>
J 0
(1865 3110);
DISPLAY 0.680851 (1865 3110);
PAINT WHITE (1865 3110);
WIRE 17 -1 (1800 3250)(1800 3350);
WIRE 17 -1 (1800 3350)(1800 3450);
WIRE 17 -1 (1800 3450)(1800 3550);
WIRE 17 -1 (1800 3650)(1800 3550);
WIRE 17 -1 (1800 3650)(1800 3750);
WIRE 17 -1 (1800 3750)(1800 3850);
WIRE 17 -1 (1800 3850)(1800 3950);
WIRE 17 -1 (1800 3950)(1800 4050);
WIRE 17 -1 (1800 4050)(1800 4150);
WIRE 17 -1 (1800 4150)(2650 4150);
FORCEPROP 2 LAST SIG_NAME M_C_CPU1_SA_DQS_DN<9:0>
J 0
(1865 4160);
DISPLAY 0.680851 (1865 4160);
PAINT WHITE (1865 4160);
WIRE 16 -1 (550 400)(550 575);
WIRE 16 -1 (1550 575)(1550 525);
WIRE 16 -1 (3250 4675)(3250 4175);
WIRE 16 -1 (-3650 2000)(-3650 1725);
WIRE 16 -1 (-2600 -150)(-2600 -75);
WIRE 16 -1 (550 200)(550 -25);
WIRE 16 -1 (2175 -25)(2175 50);
WIRE 16 -1 (3250 525)(3250 925);
WIRE 16 -1 (4950 825)(4950 525);
WIRE 16 -1 (4950 875)(4950 825);
WIRE 16 -1 (4700 825)(4950 825);
WIRE 16 3135 (200 800)(200 -500);
WIRE 16 3135 (2800 800)(200 800);
WIRE 16 3135 (200 -500)(2800 -500);
WIRE 16 3135 (2800 -500)(2800 800);
WIRE 16 -1 (-4125 1450)(-3925 1450);
WIRE 16 -1 (-4125 1450)(-4125 1575);
WIRE 16 -1 (-2600 1575)(-4125 1575);
FORCEPROP 2 LAST SIG_NAME I3C_SPD_DDRABCD_CPU1_LVC1_SCL_R5
J 0
(-3660 1585);
DISPLAY 0.680851 (-3660 1585);
PAINT WHITE (-3660 1585);
WIRE 16 -1 (-2600 1625)(-3600 1625);
FORCEPROP 2 LAST SIG_NAME I3C_SPD_DDRABCD_CPU1_LVC1_SDA
J 0
(-3585 1635);
DISPLAY 0.680851 (-3585 1635);
PAINT WHITE (-3585 1635);
WIRE 16 -1 (-2600 1675)(-3600 1675);
FORCEPROP 2 LAST SIG_NAME PD_CHC_CPU1_DIMM1_SAA
J 0
(-3585 1685);
DISPLAY 0.680851 (-3585 1685);
PAINT WHITE (-3585 1685);
WIRE 16 -1 (-2600 1825)(-3700 1825);
FORCEPROP 2 LAST SIG_NAME M_C_CPU1_ALERT_N
J 0
(-3612 1834);
DISPLAY 0.680851 (-3612 1834);
PAINT WHITE (-3612 1834);
WIRE 16 -1 (-3650 1725)(-2600 1725);
WIRE 16 -1 (-2975 1925)(-3700 1925);
FORCEPROP 2 LAST SIG_NAME RST_M_CD_CPU1_FPGA_N
J 0
(-3612 1934);
DISPLAY 0.680851 (-3612 1934);
PAINT WHITE (-3612 1934);
WIRE 16 -1 (-2975 1925)(-2975 1875);
WIRE 16 -1 (-2975 1875)(-2600 1875);
WIRE 16 -1 (-2475 1400)(-2525 1400);
WIRE 16 -1 (-2475 1450)(-2475 1400);
WIRE 16 -1 (-3725 1450)(-2475 1450);
FORCEPROP 2 LAST SIG_NAME I3C_SPD_DDRABCD_CPU1_LVC1_SCL
J 0
(-3535 1460);
DISPLAY 0.680851 (-3535 1460);
PAINT WHITE (-3535 1460);
WIRE 16 -1 (-2600 1325)(-3700 1325);
FORCEPROP 2 LAST SIG_NAME PWRGD_CHC_CPU1_DIMM1
J 0
(-3612 1334);
DISPLAY 0.680851 (-3612 1334);
PAINT WHITE (-3612 1334);
WIRE 16 -1 (-2600 1225)(-3700 1225);
FORCEPROP 2 LAST SIG_NAME TP_CHC_CPU1_DIMM1_FRU_6
J 0
(-3612 1234);
DISPLAY 0.680851 (-3612 1234);
PAINT WHITE (-3612 1234);
WIRE 16 -1 (-2600 1125)(-3700 1125);
FORCEPROP 2 LAST SIG_NAME TP_CHC_CPU1_DIMM1_FRU_4
J 0
(-3612 1134);
DISPLAY 0.680851 (-3612 1134);
PAINT WHITE (-3612 1134);
WIRE 16 -1 (-2600 1175)(-3700 1175);
FORCEPROP 2 LAST SIG_NAME TP_CHC_CPU1_DIMM1_FRU_5
J 0
(-3612 1184);
DISPLAY 0.680851 (-3612 1184);
PAINT WHITE (-3612 1184);
WIRE 16 -1 (1700 2475)(1425 2475);
WIRE 16 -1 (1700 4125)(1425 4125);
WIRE 16 -1 (1700 4025)(1425 4025);
WIRE 16 -1 (1700 3925)(1425 3925);
WIRE 16 -1 (1700 3725)(1425 3725);
WIRE 16 -1 (1700 3825)(1425 3825);
WIRE 16 -1 (1700 3625)(1425 3625);
WIRE 16 -1 (1700 3525)(1425 3525);
WIRE 16 -1 (1700 3425)(1425 3425);
WIRE 16 -1 (1700 3325)(1425 3325);
WIRE 16 -1 (1700 3225)(1425 3225);
WIRE 16 -1 (1700 3075)(1425 3075);
WIRE 16 -1 (1700 2975)(1425 2975);
WIRE 16 -1 (1700 2875)(1425 2875);
WIRE 16 -1 (1700 2575)(1425 2575);
WIRE 16 -1 (1700 2775)(1425 2775);
WIRE 16 -1 (1700 2675)(1425 2675);
WIRE 16 -1 (1700 2375)(1425 2375);
WIRE 16 -1 (1700 2275)(1425 2275);
WIRE 16 -1 (1700 2175)(1425 2175);
WIRE 16 -1 (1425 4175)(1525 4175);
WIRE 16 -1 (1425 4075)(1525 4075);
WIRE 16 -1 (1425 3125)(1525 3125);
WIRE 16 -1 (1425 3275)(1525 3275);
WIRE 16 -1 (1425 3475)(1525 3475);
WIRE 16 -1 (1425 3375)(1525 3375);
WIRE 16 -1 (1425 3575)(1525 3575);
WIRE 16 -1 (1425 3675)(1525 3675);
WIRE 16 -1 (1425 3775)(1525 3775);
WIRE 16 -1 (1425 3875)(1525 3875);
WIRE 16 -1 (1425 3975)(1525 3975);
WIRE 16 -1 (1425 2325)(1525 2325);
WIRE 16 -1 (1425 2225)(1525 2225);
WIRE 16 -1 (1425 2425)(1525 2425);
WIRE 16 -1 (1425 2525)(1525 2525);
WIRE 16 -1 (1425 2625)(1525 2625);
WIRE 16 -1 (1425 2825)(1525 2825);
WIRE 16 -1 (1425 2725)(1525 2725);
WIRE 16 -1 (1425 2925)(1525 2925);
WIRE 16 -1 (1425 3025)(1525 3025);
WIRE 16 -1 (3500 4175)(3250 4175);
WIRE 16 -1 (3250 4175)(3250 4125);
WIRE 16 -1 (3250 4125)(3500 4125);
WIRE 16 -1 (3250 4125)(3250 4075);
WIRE 16 -1 (3500 4075)(3250 4075);
WIRE 16 -1 (3250 925)(3500 925);
WIRE 16 -1 (3250 925)(3250 975);
WIRE 16 -1 (3250 975)(3500 975);
WIRE 16 -1 (3250 975)(3250 1025);
WIRE 16 -1 (3250 1025)(3500 1025);
WIRE 16 -1 (3250 1025)(3250 1075);
WIRE 16 -1 (3250 1075)(3500 1075);
WIRE 16 -1 (3250 1075)(3250 1125);
WIRE 16 -1 (3250 1125)(3500 1125);
WIRE 16 -1 (3250 1125)(3250 1175);
WIRE 16 -1 (3250 1175)(3500 1175);
WIRE 16 -1 (3250 1175)(3250 1225);
WIRE 16 -1 (3250 1225)(3500 1225);
WIRE 16 -1 (3250 1225)(3250 1275);
WIRE 16 -1 (3250 1275)(3500 1275);
WIRE 16 -1 (3250 1275)(3250 1325);
WIRE 16 -1 (3250 1325)(3500 1325);
WIRE 16 -1 (3250 1325)(3250 1375);
WIRE 16 -1 (3250 1375)(3500 1375);
WIRE 16 -1 (3250 1375)(3250 1425);
WIRE 16 -1 (3500 1425)(3250 1425);
WIRE 16 -1 (3250 1425)(3250 1475);
WIRE 16 -1 (3250 1475)(3500 1475);
WIRE 16 -1 (3250 1475)(3250 1525);
WIRE 16 -1 (3250 1525)(3500 1525);
WIRE 16 -1 (3250 1525)(3250 1575);
WIRE 16 -1 (3250 1575)(3500 1575);
WIRE 16 -1 (3250 1575)(3250 1625);
WIRE 16 -1 (3250 1625)(3500 1625);
WIRE 16 -1 (3250 1625)(3250 1675);
WIRE 16 -1 (3250 1675)(3500 1675);
WIRE 16 -1 (3250 1675)(3250 1725);
WIRE 16 -1 (3250 1725)(3500 1725);
WIRE 16 -1 (3250 1725)(3250 1775);
WIRE 16 -1 (3250 1775)(3500 1775);
WIRE 16 -1 (3250 1775)(3250 1825);
WIRE 16 -1 (3250 1825)(3500 1825);
WIRE 16 -1 (3250 1825)(3250 1875);
WIRE 16 -1 (3250 1875)(3500 1875);
WIRE 16 -1 (3250 1875)(3250 1925);
WIRE 16 -1 (3500 1925)(3250 1925);
WIRE 16 -1 (3250 1925)(3250 1975);
WIRE 16 -1 (3250 1975)(3500 1975);
WIRE 16 -1 (3250 1975)(3250 2025);
WIRE 16 -1 (3250 2025)(3500 2025);
WIRE 16 -1 (3250 2025)(3250 2075);
WIRE 16 -1 (3250 2075)(3500 2075);
WIRE 16 -1 (3250 2075)(3250 2125);
WIRE 16 -1 (3250 2125)(3500 2125);
WIRE 16 -1 (3250 2125)(3250 2175);
WIRE 16 -1 (3250 2175)(3500 2175);
WIRE 16 -1 (3250 2175)(3250 2225);
WIRE 16 -1 (3250 2225)(3500 2225);
WIRE 16 -1 (3250 2225)(3250 2275);
WIRE 16 -1 (3250 2275)(3500 2275);
WIRE 16 -1 (3250 2275)(3250 2325);
WIRE 16 -1 (3250 2325)(3500 2325);
WIRE 16 -1 (3250 2325)(3250 2375);
WIRE 16 -1 (3250 2375)(3500 2375);
WIRE 16 -1 (3250 2375)(3250 2425);
WIRE 16 -1 (3500 2425)(3250 2425);
WIRE 16 -1 (3250 2425)(3250 2475);
WIRE 16 -1 (3250 2475)(3500 2475);
WIRE 16 -1 (3250 2475)(3250 2525);
WIRE 16 -1 (3250 2525)(3500 2525);
WIRE 16 -1 (3250 2525)(3250 2575);
WIRE 16 -1 (3250 2575)(3500 2575);
WIRE 16 -1 (3250 2575)(3250 2625);
WIRE 16 -1 (3250 2625)(3500 2625);
WIRE 16 -1 (3250 2625)(3250 2675);
WIRE 16 -1 (3250 2675)(3500 2675);
WIRE 16 -1 (3250 2675)(3250 2725);
WIRE 16 -1 (3250 2725)(3500 2725);
WIRE 16 -1 (3250 2725)(3250 2775);
WIRE 16 -1 (3250 2775)(3500 2775);
WIRE 16 -1 (3250 2775)(3250 2825);
WIRE 16 -1 (3250 2825)(3500 2825);
WIRE 16 -1 (3250 2825)(3250 2875);
WIRE 16 -1 (3250 2875)(3500 2875);
WIRE 16 -1 (3250 2875)(3250 2925);
WIRE 16 -1 (3500 2925)(3250 2925);
WIRE 16 -1 (3250 2925)(3250 2975);
WIRE 16 -1 (3250 2975)(3500 2975);
WIRE 16 -1 (3250 2975)(3250 3025);
WIRE 16 -1 (3250 3025)(3500 3025);
WIRE 16 -1 (3250 3025)(3250 3075);
WIRE 16 -1 (3250 3075)(3500 3075);
WIRE 16 -1 (3250 3075)(3250 3125);
WIRE 16 -1 (3250 3125)(3500 3125);
WIRE 16 -1 (3250 3125)(3250 3175);
WIRE 16 -1 (3250 3175)(3500 3175);
WIRE 16 -1 (3250 3175)(3250 3225);
WIRE 16 -1 (3250 3225)(3500 3225);
WIRE 16 -1 (3250 3225)(3250 3275);
WIRE 16 -1 (3250 3275)(3500 3275);
WIRE 16 -1 (3250 3275)(3250 3325);
WIRE 16 -1 (3250 3325)(3500 3325);
WIRE 16 -1 (3250 3325)(3250 3375);
WIRE 16 -1 (3250 3375)(3500 3375);
WIRE 16 -1 (3250 3375)(3250 3425);
WIRE 16 -1 (3500 3425)(3250 3425);
WIRE 16 -1 (3250 3425)(3250 3475);
WIRE 16 -1 (3250 3475)(3500 3475);
WIRE 16 -1 (3250 3475)(3250 3525);
WIRE 16 -1 (3250 3525)(3500 3525);
WIRE 16 -1 (3250 3525)(3250 3575);
WIRE 16 -1 (3250 3575)(3500 3575);
WIRE 16 -1 (3250 3575)(3250 3625);
WIRE 16 -1 (3250 3625)(3500 3625);
WIRE 16 -1 (3250 3625)(3250 3675);
WIRE 16 -1 (3250 3675)(3500 3675);
WIRE 16 -1 (3250 3675)(3250 3725);
WIRE 16 -1 (3250 3725)(3500 3725);
WIRE 16 -1 (3250 3725)(3250 3775);
WIRE 16 -1 (3250 3775)(3500 3775);
WIRE 16 -1 (3250 3775)(3250 3825);
WIRE 16 -1 (3250 3825)(3500 3825);
WIRE 16 -1 (3250 3825)(3250 3875);
WIRE 16 -1 (3250 3875)(3500 3875);
WIRE 16 -1 (3250 3875)(3250 3925);
WIRE 16 -1 (3500 3925)(3250 3925);
WIRE 16 -1 (3250 3925)(3250 3975);
WIRE 16 -1 (3250 3975)(3500 3975);
WIRE 16 -1 (3250 3975)(3250 4025);
WIRE 16 -1 (3500 4025)(3250 4025);
WIRE 16 -1 (-1400 3775)(-1225 3775);
WIRE 16 -1 (-1400 3825)(-1225 3825);
WIRE 16 -1 (-1400 4025)(-1225 4025);
WIRE 16 -1 (-2600 3025)(-3700 3025);
FORCEPROP 2 LAST SIG_NAME M_C_CPU1_SB_CS_N<0>
J 0
(-3612 3034);
DISPLAY 0.680851 (-3612 3034);
PAINT WHITE (-3612 3034);
WIRE 16 -1 (-2600 2875)(-3700 2875);
FORCEPROP 2 LAST SIG_NAME M_C_CPU1_CLK_DN<0>
J 0
(-3612 2884);
DISPLAY 0.680851 (-3612 2884);
PAINT WHITE (-3612 2884);
WIRE 16 -1 (-2775 2775)(-2600 2775);
WIRE 16 -1 (-1400 2425)(-1225 2425);
WIRE 16 -1 (-1400 2325)(-1225 2325);
WIRE 16 -1 (-1400 2375)(-1225 2375);
WIRE 16 -1 (-2600 925)(-3700 925);
FORCEPROP 2 LAST SIG_NAME TP_CHC_CPU1_DIMM1_FRU_0
J 0
(-3612 934);
DISPLAY 0.680851 (-3612 934);
PAINT WHITE (-3612 934);
WIRE 16 -1 (-2600 975)(-3700 975);
FORCEPROP 2 LAST SIG_NAME TP_CHC_CPU1_DIMM1_FRU_1
J 0
(-3612 984);
DISPLAY 0.680851 (-3612 984);
PAINT WHITE (-3612 984);
WIRE 16 -1 (-2600 1025)(-3700 1025);
FORCEPROP 2 LAST SIG_NAME TP_CHC_CPU1_DIMM1_FRU_2
J 0
(-3612 1034);
DISPLAY 0.680851 (-3612 1034);
PAINT WHITE (-3612 1034);
WIRE 16 -1 (-2600 1075)(-3700 1075);
FORCEPROP 2 LAST SIG_NAME TP_CHC_CPU1_DIMM1_FRU_3
J 0
(-3612 1084);
DISPLAY 0.680851 (-3612 1084);
PAINT WHITE (-3612 1084);
WIRE 16 -1 (-2600 3325)(-3700 3325);
FORCEPROP 2 LAST SIG_NAME M_C_CPU1_SB_PAR
J 0
(-3612 3334);
DISPLAY 0.680851 (-3612 3334);
PAINT WHITE (-3612 3334);
WIRE 16 -1 (-2600 3375)(-3700 3375);
FORCEPROP 2 LAST SIG_NAME M_C_CPU1_SA_PAR
J 0
(-3612 3384);
DISPLAY 0.680851 (-3612 3384);
PAINT WHITE (-3612 3384);
WIRE 16 -1 (-2600 725)(-3700 725);
FORCEPROP 2 LAST SIG_NAME M_C_CPU1_SB_RSP<0>
J 0
(-3612 734);
DISPLAY 0.680851 (-3612 734);
PAINT WHITE (-3612 734);
WIRE 16 -1 (-2600 775)(-3700 775);
FORCEPROP 2 LAST SIG_NAME M_C_CPU1_SA_RSP<0>
J 0
(-3612 784);
DISPLAY 0.680851 (-3612 784);
PAINT WHITE (-3612 784);
WIRE 16 -1 (-1400 975)(-1225 975);
WIRE 16 -1 (-1400 1025)(-1225 1025);
WIRE 16 -1 (-1400 1075)(-1225 1075);
WIRE 16 -1 (-1400 1125)(-1225 1125);
WIRE 16 -1 (-1400 1175)(-1225 1175);
WIRE 16 -1 (-1400 1225)(-1225 1225);
WIRE 16 -1 (-1400 1275)(-1225 1275);
WIRE 16 -1 (-1400 1325)(-1225 1325);
WIRE 16 -1 (-1400 1375)(-1225 1375);
WIRE 16 -1 (-1400 1425)(-1225 1425);
WIRE 16 -1 (-1400 1475)(-1225 1475);
WIRE 16 -1 (-1400 1525)(-1225 1525);
WIRE 16 -1 (-1400 1575)(-1225 1575);
WIRE 16 -1 (-1400 1625)(-1225 1625);
WIRE 16 -1 (-1400 1675)(-1225 1675);
WIRE 16 -1 (-1400 1725)(-1225 1725);
WIRE 16 -1 (-1400 1775)(-1225 1775);
WIRE 16 -1 (-1400 1825)(-1225 1825);
WIRE 16 -1 (-1400 1875)(-1225 1875);
WIRE 16 -1 (-1400 1925)(-1225 1925);
WIRE 16 -1 (-1400 1975)(-1225 1975);
WIRE 16 -1 (-1400 2025)(-1225 2025);
WIRE 16 -1 (-1400 2075)(-1225 2075);
WIRE 16 -1 (-1400 2125)(-1225 2125);
WIRE 16 -1 (-1400 2175)(-1225 2175);
WIRE 16 -1 (-1400 2225)(-1225 2225);
WIRE 16 -1 (-1400 2275)(-1225 2275);
WIRE 16 -1 (-1400 2475)(-1225 2475);
WIRE 16 -1 (-1400 2525)(-1225 2525);
WIRE 16 -1 (-1400 2625)(-1225 2625);
WIRE 16 -1 (-1400 2675)(-1225 2675);
WIRE 16 -1 (-1400 2725)(-1225 2725);
WIRE 16 -1 (-1400 2775)(-1225 2775);
WIRE 16 -1 (-1400 2825)(-1225 2825);
WIRE 16 -1 (-1400 2875)(-1225 2875);
WIRE 16 -1 (-1400 2925)(-1225 2925);
WIRE 16 -1 (-1400 2975)(-1225 2975);
WIRE 16 -1 (-1400 3025)(-1225 3025);
WIRE 16 -1 (-1400 3075)(-1225 3075);
WIRE 16 -1 (-1400 3125)(-1225 3125);
WIRE 16 -1 (-1400 3175)(-1225 3175);
WIRE 16 -1 (-1400 3225)(-1225 3225);
WIRE 16 -1 (-1400 3275)(-1225 3275);
WIRE 16 -1 (-1400 3325)(-1225 3325);
WIRE 16 -1 (-1400 3375)(-1225 3375);
WIRE 16 -1 (-1400 3425)(-1225 3425);
WIRE 16 -1 (-1400 3475)(-1225 3475);
WIRE 16 -1 (-1400 3525)(-1225 3525);
WIRE 16 -1 (-1400 3575)(-1225 3575);
WIRE 16 -1 (-1400 3625)(-1225 3625);
WIRE 16 -1 (-1400 3675)(-1225 3675);
WIRE 16 -1 (-1400 3725)(-1225 3725);
WIRE 16 -1 (-1400 3875)(-1225 3875);
WIRE 16 -1 (-1400 3925)(-1225 3925);
WIRE 16 -1 (-1400 3975)(-1225 3975);
WIRE 16 -1 (-1400 4075)(-1225 4075);
WIRE 16 -1 (-1400 4125)(-1225 4125);
WIRE 16 -1 (-2600 3075)(-3700 3075);
FORCEPROP 2 LAST SIG_NAME M_C_CPU1_SB_CS_N<1>
J 0
(-3612 3084);
DISPLAY 0.680851 (-3612 3084);
PAINT WHITE (-3612 3084);
WIRE 16 -1 (-2600 3225)(-3700 3225);
FORCEPROP 2 LAST SIG_NAME M_C_CPU1_SA_CS_N<1>
J 0
(-3612 3234);
DISPLAY 0.680851 (-3612 3234);
PAINT WHITE (-3612 3234);
WIRE 16 -1 (-2600 3175)(-3700 3175);
FORCEPROP 2 LAST SIG_NAME M_C_CPU1_SA_CS_N<0>
J 0
(-3612 3184);
DISPLAY 0.680851 (-3612 3184);
PAINT WHITE (-3612 3184);
WIRE 16 -1 (-2600 2925)(-3700 2925);
FORCEPROP 2 LAST SIG_NAME M_C_CPU1_CLK_DP<0>
J 0
(-3612 2934);
DISPLAY 0.680851 (-3612 2934);
PAINT WHITE (-3612 2934);
WIRE 16 -1 (-2775 1975)(-2600 1975);
WIRE 16 -1 (-2775 2025)(-2600 2025);
WIRE 16 -1 (-2775 2075)(-2600 2075);
WIRE 16 -1 (-2775 2125)(-2600 2125);
WIRE 16 -1 (-2775 2175)(-2600 2175);
WIRE 16 -1 (-2775 2225)(-2600 2225);
WIRE 16 -1 (-2775 2275)(-2600 2275);
WIRE 16 -1 (-2775 2425)(-2600 2425);
WIRE 16 -1 (-2775 2525)(-2600 2525);
WIRE 16 -1 (-2775 2575)(-2600 2575);
WIRE 16 -1 (-2775 2675)(-2600 2675);
WIRE 16 -1 (-2775 2725)(-2600 2725);
WIRE 16 -1 (-2775 3775)(-2600 3775);
WIRE 16 -1 (-2775 4175)(-2600 4175);
WIRE 16 -1 (-2775 3725)(-2600 3725);
WIRE 16 -1 (-2775 4125)(-2600 4125);
WIRE 16 -1 (-2775 3675)(-2600 3675);
WIRE 16 -1 (-2775 4075)(-2600 4075);
WIRE 16 -1 (-2775 3625)(-2600 3625);
WIRE 16 -1 (-2775 4025)(-2600 4025);
WIRE 16 -1 (-2775 3575)(-2600 3575);
WIRE 16 -1 (-2775 3975)(-2600 3975);
WIRE 16 -1 (-2775 3525)(-2600 3525);
WIRE 16 -1 (-2775 3925)(-2600 3925);
WIRE 16 -1 (-2775 3475)(-2600 3475);
WIRE 16 -1 (-2775 3875)(-2600 3875);
WIRE 16 -1 (-2775 2325)(-2600 2325);
WIRE 16 -1 (-2775 2475)(-2600 2475);
WIRE 16 -1 (-2775 2625)(-2600 2625);
WIRE 16 -1 (-1400 4175)(-1225 4175);
WIRE 16 -1 (4700 4175)(4950 4175);
WIRE 16 -1 (4950 4175)(4950 4125);
WIRE 16 -1 (4700 4125)(4950 4125);
WIRE 16 -1 (4700 4075)(4950 4075);
WIRE 16 -1 (4950 4125)(4950 4075);
WIRE 16 -1 (4700 4025)(4950 4025);
WIRE 16 -1 (4950 4075)(4950 4025);
WIRE 16 -1 (4700 3975)(4950 3975);
WIRE 16 -1 (4950 4025)(4950 3975);
WIRE 16 -1 (4700 3925)(4950 3925);
WIRE 16 -1 (4950 3975)(4950 3925);
WIRE 16 -1 (4700 3875)(4950 3875);
WIRE 16 -1 (4950 3925)(4950 3875);
WIRE 16 -1 (4700 3825)(4950 3825);
WIRE 16 -1 (4950 3875)(4950 3825);
WIRE 16 -1 (4700 3775)(4950 3775);
WIRE 16 -1 (4950 3825)(4950 3775);
WIRE 16 -1 (4700 3725)(4950 3725);
WIRE 16 -1 (4950 3775)(4950 3725);
WIRE 16 -1 (4700 3675)(4950 3675);
WIRE 16 -1 (4950 3725)(4950 3675);
WIRE 16 -1 (4700 3625)(4950 3625);
WIRE 16 -1 (4950 3675)(4950 3625);
WIRE 16 -1 (4700 3575)(4950 3575);
WIRE 16 -1 (4950 3625)(4950 3575);
WIRE 16 -1 (4700 3525)(4950 3525);
WIRE 16 -1 (4950 3575)(4950 3525);
WIRE 16 -1 (4700 3475)(4950 3475);
WIRE 16 -1 (4950 3525)(4950 3475);
WIRE 16 -1 (4700 3425)(4950 3425);
WIRE 16 -1 (4950 3425)(4950 3475);
WIRE 16 -1 (4700 3375)(4950 3375);
WIRE 16 -1 (4950 3425)(4950 3375);
WIRE 16 -1 (4950 3325)(4700 3325);
WIRE 16 -1 (4950 3375)(4950 3325);
WIRE 16 -1 (4950 3275)(4700 3275);
WIRE 16 -1 (4950 3325)(4950 3275);
WIRE 16 -1 (4700 3225)(4950 3225);
WIRE 16 -1 (4950 3275)(4950 3225);
WIRE 16 -1 (4700 3175)(4950 3175);
WIRE 16 -1 (4950 3225)(4950 3175);
WIRE 16 -1 (4700 3125)(4950 3125);
WIRE 16 -1 (4950 3175)(4950 3125);
WIRE 16 -1 (4700 3075)(4950 3075);
WIRE 16 -1 (4950 3125)(4950 3075);
WIRE 16 -1 (4700 3025)(4950 3025);
WIRE 16 -1 (4950 3075)(4950 3025);
WIRE 16 -1 (4700 2975)(4950 2975);
WIRE 16 -1 (4950 3025)(4950 2975);
WIRE 16 -1 (4700 2925)(4950 2925);
WIRE 16 -1 (4950 2925)(4950 2975);
WIRE 16 -1 (4700 2875)(4950 2875);
WIRE 16 -1 (4950 2925)(4950 2875);
WIRE 16 -1 (4950 2825)(4700 2825);
WIRE 16 -1 (4950 2875)(4950 2825);
WIRE 16 -1 (4950 2775)(4700 2775);
WIRE 16 -1 (4950 2825)(4950 2775);
WIRE 16 -1 (4700 2725)(4950 2725);
WIRE 16 -1 (4950 2775)(4950 2725);
WIRE 16 -1 (4700 2675)(4950 2675);
WIRE 16 -1 (4950 2725)(4950 2675);
WIRE 16 -1 (4700 2625)(4950 2625);
WIRE 16 -1 (4950 2675)(4950 2625);
WIRE 16 -1 (4700 2575)(4950 2575);
WIRE 16 -1 (4950 2625)(4950 2575);
WIRE 16 -1 (4700 2525)(4950 2525);
WIRE 16 -1 (4950 2575)(4950 2525);
WIRE 16 -1 (4700 2475)(4950 2475);
WIRE 16 -1 (4950 2525)(4950 2475);
WIRE 16 -1 (4700 2425)(4950 2425);
WIRE 16 -1 (4950 2425)(4950 2475);
WIRE 16 -1 (4700 2375)(4950 2375);
WIRE 16 -1 (4950 2425)(4950 2375);
WIRE 16 -1 (4950 2325)(4700 2325);
WIRE 16 -1 (4950 2375)(4950 2325);
WIRE 16 -1 (4950 2275)(4700 2275);
WIRE 16 -1 (4950 2325)(4950 2275);
WIRE 16 -1 (4700 2225)(4950 2225);
WIRE 16 -1 (4950 2275)(4950 2225);
WIRE 16 -1 (4700 2175)(4950 2175);
WIRE 16 -1 (4950 2225)(4950 2175);
WIRE 16 -1 (4700 2125)(4950 2125);
WIRE 16 -1 (4950 2175)(4950 2125);
WIRE 16 -1 (4700 2075)(4950 2075);
WIRE 16 -1 (4950 2125)(4950 2075);
WIRE 16 -1 (4700 2025)(4950 2025);
WIRE 16 -1 (4950 2075)(4950 2025);
WIRE 16 -1 (4700 1975)(4950 1975);
WIRE 16 -1 (4950 2025)(4950 1975);
WIRE 16 -1 (4700 1925)(4950 1925);
WIRE 16 -1 (4950 1925)(4950 1975);
WIRE 16 -1 (4700 1875)(4950 1875);
WIRE 16 -1 (4950 1925)(4950 1875);
WIRE 16 -1 (4950 1825)(4700 1825);
WIRE 16 -1 (4950 1875)(4950 1825);
WIRE 16 -1 (4950 1775)(4700 1775);
WIRE 16 -1 (4950 1825)(4950 1775);
WIRE 16 -1 (4950 1725)(4700 1725);
WIRE 16 -1 (4950 1775)(4950 1725);
WIRE 16 -1 (4950 1675)(4700 1675);
WIRE 16 -1 (4950 1725)(4950 1675);
WIRE 16 -1 (4700 1625)(4950 1625);
WIRE 16 -1 (4950 1625)(4950 1675);
WIRE 16 -1 (4950 1575)(4700 1575);
WIRE 16 -1 (4950 1575)(4950 1625);
WIRE 16 -1 (4950 1525)(4700 1525);
WIRE 16 -1 (4950 1575)(4950 1525);
WIRE 16 -1 (4950 1475)(4700 1475);
WIRE 16 -1 (4950 1525)(4950 1475);
WIRE 16 -1 (4700 1425)(4950 1425);
WIRE 16 -1 (4950 1475)(4950 1425);
WIRE 16 -1 (4700 1375)(4950 1375);
WIRE 16 -1 (4950 1425)(4950 1375);
WIRE 16 -1 (4700 1325)(4950 1325);
WIRE 16 -1 (4950 1375)(4950 1325);
WIRE 16 -1 (4700 1275)(4950 1275);
WIRE 16 -1 (4950 1325)(4950 1275);
WIRE 16 -1 (4700 1225)(4950 1225);
WIRE 16 -1 (4950 1275)(4950 1225);
WIRE 16 -1 (4700 1175)(4950 1175);
WIRE 16 -1 (4950 1225)(4950 1175);
WIRE 16 -1 (4700 1125)(4950 1125);
WIRE 16 -1 (4950 1175)(4950 1125);
WIRE 16 -1 (4700 1075)(4950 1075);
WIRE 16 -1 (4950 1075)(4950 1125);
WIRE 16 -1 (4700 1025)(4950 1025);
WIRE 16 -1 (4950 1075)(4950 1025);
WIRE 16 -1 (4700 925)(4950 925);
WIRE 16 -1 (4950 1025)(4950 925);
WIRE 16 -1 (4950 925)(4950 875);
WIRE 16 -1 (4700 875)(4950 875);
WIRE 16 -1 (-2600 225)(-3700 225);
FORCEPROP 2 LAST SIG_NAME PD_CHC_CPU1_DIMM1_SAA
J 0
(-3612 234);
DISPLAY 0.680851 (-3612 234);
PAINT WHITE (-3612 234);
WIRE 16 -1 (-2600 125)(-2600 225);
WIRE 16 -1 (1550 525)(1550 400);
WIRE 16 -1 (2175 525)(1550 525);
WIRE 16 -1 (2175 400)(2175 525);
WIRE 16 -1 (1550 50)(1550 200);
WIRE 16 -1 (2175 50)(1550 50);
WIRE 16 -1 (2175 50)(2175 200);
DOT 1 (4950 825);
DOT 1 (4950 875);
DOT 1 (4950 925);
DOT 1 (4950 4125);
DOT 1 (4950 4075);
DOT 1 (4950 4025);
DOT 1 (4950 3975);
DOT 1 (4950 3925);
DOT 1 (4950 3875);
DOT 1 (4950 3825);
DOT 1 (4950 3775);
DOT 1 (4950 3725);
DOT 1 (4950 3625);
DOT 1 (4950 3675);
DOT 1 (4950 3575);
DOT 1 (4950 3525);
DOT 1 (4950 3475);
DOT 1 (4950 3425);
DOT 1 (4950 3375);
DOT 1 (4950 3325);
DOT 1 (4950 3275);
DOT 1 (4950 3225);
DOT 1 (4950 3175);
DOT 1 (4950 3125);
DOT 1 (4950 3075);
DOT 1 (4950 3025);
DOT 1 (4950 2975);
DOT 1 (4950 2925);
DOT 1 (4950 2875);
DOT 1 (4950 2825);
DOT 1 (4950 2775);
DOT 1 (4950 2725);
DOT 1 (4950 2675);
DOT 1 (4950 2625);
DOT 1 (4950 2575);
DOT 1 (4950 2525);
DOT 1 (4950 2475);
DOT 1 (4950 2425);
DOT 1 (4950 2375);
DOT 1 (4950 2325);
DOT 1 (4950 2275);
DOT 1 (4950 2225);
DOT 1 (4950 2175);
DOT 1 (4950 2125);
DOT 1 (4950 2075);
DOT 1 (4950 2025);
DOT 1 (4950 1975);
DOT 1 (4950 1925);
DOT 1 (4950 1875);
DOT 1 (4950 1825);
DOT 1 (4950 1775);
DOT 1 (4950 1725);
DOT 1 (4950 1675);
DOT 1 (4950 1625);
DOT 1 (4950 1575);
DOT 1 (4950 1525);
DOT 1 (4950 1475);
DOT 1 (4950 1425);
DOT 1 (4950 1375);
DOT 1 (4950 1325);
DOT 1 (4950 1275);
DOT 1 (4950 1225);
DOT 1 (4950 1175);
DOT 1 (4950 1125);
DOT 1 (4950 1075);
DOT 1 (4950 1025);
DOT 1 (3250 4125);
DOT 1 (3250 4175);
DOT 1 (3250 3975);
DOT 1 (3250 3925);
DOT 1 (3250 3875);
DOT 1 (3250 3825);
DOT 1 (3250 3575);
DOT 1 (3250 3525);
DOT 1 (3250 3475);
DOT 1 (3250 3425);
DOT 1 (3250 3325);
DOT 1 (3250 3275);
DOT 1 (3250 3225);
DOT 1 (3250 3175);
DOT 1 (3250 3075);
DOT 1 (3250 3025);
DOT 1 (3250 2975);
DOT 1 (3250 2925);
DOT 1 (3250 2875);
DOT 1 (3250 2825);
DOT 1 (3250 2775);
DOT 1 (3250 2725);
DOT 1 (3250 2675);
DOT 1 (3250 2625);
DOT 1 (3250 2575);
DOT 1 (3250 2525);
DOT 1 (3250 2475);
DOT 1 (3250 2425);
DOT 1 (3250 2375);
DOT 1 (3250 2325);
DOT 1 (3250 2275);
DOT 1 (3250 2225);
DOT 1 (3250 2175);
DOT 1 (3250 2125);
DOT 1 (3250 2075);
DOT 1 (3250 2025);
DOT 1 (3250 1975);
DOT 1 (3250 1925);
DOT 1 (3250 1875);
DOT 1 (3250 1825);
DOT 1 (3250 1775);
DOT 1 (3250 1725);
DOT 1 (3250 1675);
DOT 1 (3250 1625);
DOT 1 (3250 1575);
DOT 1 (3250 1525);
DOT 1 (3250 1475);
DOT 1 (3250 1425);
DOT 1 (3250 1325);
DOT 1 (3250 1375);
DOT 1 (3250 1275);
DOT 1 (3250 1225);
DOT 1 (3250 1175);
DOT 1 (3250 1125);
DOT 1 (3250 1075);
DOT 1 (3250 1025);
DOT 1 (3250 925);
DOT 1 (3250 975);
DOT 1 (2175 50);
DOT 1 (1550 525);
DOT 1 (3250 3675);
DOT 1 (3250 3725);
DOT 1 (3250 3625);
DOT 1 (3250 3375);
DOT 1 (3250 3125);
DOT 1 (3250 3775);
FORCENOTE
20210728 MODIFY FOR GT
(-4075 4850) 0;
DISPLAY LEFT (-4075 4850);
DISPLAY 2.510638 (-4075 4850);
PAINT PINK (-4075 4850);
QUIT
